FILE_TYPE = MACRO_DRAWING;
SET COLOR_WIRE YELLOW;
SET COLOR_PROP ORANGE;
SET COLOR_DOT WHITE;
SET COLOR_ARC YELLOW;
SET COLOR_BODY GREEN;
SET COLOR_NOTE PURPLE;
SET PROP_DISPLAY VALUE;
SET PAGE_NUMBER P104;
FORCEADD OFFPAGE..5
(-8250 2000);
FORCEPROP 2 LAST $XR0 44 
J 0
(-8474 2000);
DISPLAY 0.638298 (-8474 2000);
PAINT MONO (-8474 2000);
FORCEPROP 2 LAST CDS_LIB mstr_standard
J 0
(-8250 2000);
DISPLAY 0.808511 (-8250 2000);
DISPLAY INVISIBLE (-8250 2000);
FORCEPROP 1 LAST OFFPAGE TRUE
J 0
(-7925 1875);
DISPLAY 0.872340 (-7925 1875);
PAINT GREEN (-7925 1875);
DISPLAY INVISIBLE (-7925 1875);
FORCEPROP 1 LAST COMMENT_BODY TRUE
J 0
(-8150 1925);
DISPLAY 0.872340 (-8150 1925);
PAINT GREEN (-8150 1925);
DISPLAY INVISIBLE (-8150 1925);
FORCEPROP 2 LAST PATH I1
J 0
(-8500 2050);
DISPLAY 1.021277 (-8500 2050);
DISPLAY INVISIBLE (-8500 2050);
FORCEADD OFFPAGE..6
(-8250 3600);
FORCEPROP 2 LAST $XR0 44 
J 0
(-8529 3600);
DISPLAY 0.638298 (-8529 3600);
PAINT MONO (-8529 3600);
FORCEPROP 2 LAST CDS_LIB mstr_standard
J 0
(-8250 3600);
DISPLAY 0.723404 (-8250 3600);
PAINT MONO (-8250 3600);
DISPLAY INVISIBLE (-8250 3600);
FORCEPROP 1 LAST OFFPAGE TRUE
J 0
(-7925 3475);
DISPLAY 0.872340 (-7925 3475);
PAINT GREEN (-7925 3475);
DISPLAY INVISIBLE (-7925 3475);
FORCEPROP 1 LAST COMMENT_BODY TRUE
J 0
(-8150 3525);
DISPLAY 0.872340 (-8150 3525);
PAINT GREEN (-8150 3525);
DISPLAY INVISIBLE (-8150 3525);
FORCEPROP 2 LAST PATH I10
J 0
(-8525 3650);
DISPLAY 1.021277 (-8525 3650);
DISPLAY INVISIBLE (-8525 3650);
FORCEADD TAP..1
(-5950 4200);
FORCEPROP 3 LASTPIN (-6000 4200) SIG_NAME M_H_CPU1_SA_DQ<7>
J 0
(-5990 4210);
DISPLAY 0.659574 (-5990 4210);
PAINT MONO (-5990 4210);
DISPLAY INVISIBLE (-5990 4210);
FORCEPROP 1 LASTPIN (-6000 4200) BN 7
J 0
(-6012 4208);
DISPLAY 0.489362 (-6012 4208);
PAINT GREEN (-6012 4208);
FORCEPROP 2 LAST CDS_LIB mstr_standard
J 0
(-5950 4200);
DISPLAY 0.723404 (-5950 4200);
PAINT MONO (-5950 4200);
DISPLAY INVISIBLE (-5950 4200);
FORCEPROP 1 LAST BODY_TYPE PLUMBING
J 0
(-5950 4250);
DISPLAY 0.872340 (-5950 4250);
PAINT GREEN (-5950 4250);
DISPLAY INVISIBLE (-5950 4250);
FORCEPROP 1 LAST HDL_TAP TRUE
J 0
(-5625 4075);
DISPLAY 0.872340 (-5625 4075);
DISPLAY INVISIBLE (-5625 4075);
FORCEPROP 1 LAST PATH I100
J 0
(-5952 4200);
DISPLAY 0.872340 (-5952 4200);
PAINT GREEN (-5952 4200);
DISPLAY INVISIBLE (-5952 4200);
FORCEADD TAP..1
(-5950 4250);
FORCEPROP 3 LASTPIN (-6000 4250) SIG_NAME M_H_CPU1_SA_DQ<8>
J 0
(-5990 4260);
DISPLAY 0.659574 (-5990 4260);
PAINT MONO (-5990 4260);
DISPLAY INVISIBLE (-5990 4260);
FORCEPROP 1 LASTPIN (-6000 4250) BN 8
J 0
(-6012 4258);
DISPLAY 0.489362 (-6012 4258);
PAINT GREEN (-6012 4258);
FORCEPROP 2 LAST CDS_LIB mstr_standard
J 0
(-5950 4250);
DISPLAY 0.723404 (-5950 4250);
PAINT MONO (-5950 4250);
DISPLAY INVISIBLE (-5950 4250);
FORCEPROP 1 LAST BODY_TYPE PLUMBING
J 0
(-5950 4300);
DISPLAY 0.872340 (-5950 4300);
PAINT GREEN (-5950 4300);
DISPLAY INVISIBLE (-5950 4300);
FORCEPROP 1 LAST HDL_TAP TRUE
J 0
(-5625 4125);
DISPLAY 0.872340 (-5625 4125);
DISPLAY INVISIBLE (-5625 4125);
FORCEPROP 1 LAST PATH I101
J 0
(-5952 4250);
DISPLAY 0.872340 (-5952 4250);
PAINT GREEN (-5952 4250);
DISPLAY INVISIBLE (-5952 4250);
FORCEADD TAP..1
(-5950 4300);
FORCEPROP 3 LASTPIN (-6000 4300) SIG_NAME M_H_CPU1_SA_DQ<9>
J 0
(-5990 4310);
DISPLAY 0.659574 (-5990 4310);
PAINT MONO (-5990 4310);
DISPLAY INVISIBLE (-5990 4310);
FORCEPROP 1 LASTPIN (-6000 4300) BN 9
J 0
(-6012 4308);
DISPLAY 0.489362 (-6012 4308);
PAINT GREEN (-6012 4308);
FORCEPROP 2 LAST CDS_LIB mstr_standard
J 0
(-5950 4300);
DISPLAY 0.723404 (-5950 4300);
PAINT MONO (-5950 4300);
DISPLAY INVISIBLE (-5950 4300);
FORCEPROP 1 LAST BODY_TYPE PLUMBING
J 0
(-5950 4350);
DISPLAY 0.872340 (-5950 4350);
PAINT GREEN (-5950 4350);
DISPLAY INVISIBLE (-5950 4350);
FORCEPROP 1 LAST HDL_TAP TRUE
J 0
(-5625 4175);
DISPLAY 0.872340 (-5625 4175);
DISPLAY INVISIBLE (-5625 4175);
FORCEPROP 1 LAST PATH I102
J 0
(-5952 4300);
DISPLAY 0.872340 (-5952 4300);
PAINT GREEN (-5952 4300);
DISPLAY INVISIBLE (-5952 4300);
FORCEADD TAP..1
(-5950 4400);
FORCEPROP 3 LASTPIN (-6000 4400) SIG_NAME M_H_CPU1_SA_DQ<11>
J 0
(-5990 4410);
DISPLAY 0.659574 (-5990 4410);
PAINT MONO (-5990 4410);
DISPLAY INVISIBLE (-5990 4410);
FORCEPROP 1 LASTPIN (-6000 4400) BN 11
J 0
(-6012 4408);
DISPLAY 0.489362 (-6012 4408);
PAINT GREEN (-6012 4408);
FORCEPROP 2 LAST CDS_LIB mstr_standard
J 0
(-5950 4400);
DISPLAY 0.723404 (-5950 4400);
PAINT MONO (-5950 4400);
DISPLAY INVISIBLE (-5950 4400);
FORCEPROP 1 LAST BODY_TYPE PLUMBING
J 0
(-5950 4450);
DISPLAY 0.872340 (-5950 4450);
PAINT GREEN (-5950 4450);
DISPLAY INVISIBLE (-5950 4450);
FORCEPROP 1 LAST HDL_TAP TRUE
J 0
(-5625 4275);
DISPLAY 0.872340 (-5625 4275);
DISPLAY INVISIBLE (-5625 4275);
FORCEPROP 1 LAST PATH I103
J 0
(-5952 4400);
DISPLAY 0.872340 (-5952 4400);
PAINT GREEN (-5952 4400);
DISPLAY INVISIBLE (-5952 4400);
FORCEADD TAP..1
(-5950 4350);
FORCEPROP 3 LASTPIN (-6000 4350) SIG_NAME M_H_CPU1_SA_DQ<10>
J 0
(-5990 4360);
DISPLAY 0.659574 (-5990 4360);
PAINT MONO (-5990 4360);
DISPLAY INVISIBLE (-5990 4360);
FORCEPROP 1 LASTPIN (-6000 4350) BN 10
J 0
(-6012 4358);
DISPLAY 0.489362 (-6012 4358);
PAINT GREEN (-6012 4358);
FORCEPROP 2 LAST CDS_LIB mstr_standard
J 0
(-5950 4350);
DISPLAY 0.723404 (-5950 4350);
PAINT MONO (-5950 4350);
DISPLAY INVISIBLE (-5950 4350);
FORCEPROP 1 LAST BODY_TYPE PLUMBING
J 0
(-5950 4400);
DISPLAY 0.872340 (-5950 4400);
PAINT GREEN (-5950 4400);
DISPLAY INVISIBLE (-5950 4400);
FORCEPROP 1 LAST HDL_TAP TRUE
J 0
(-5625 4225);
DISPLAY 0.872340 (-5625 4225);
DISPLAY INVISIBLE (-5625 4225);
FORCEPROP 1 LAST PATH I104
J 0
(-5952 4350);
DISPLAY 0.872340 (-5952 4350);
PAINT GREEN (-5952 4350);
DISPLAY INVISIBLE (-5952 4350);
FORCEADD TAP..1
(-5950 4450);
FORCEPROP 3 LASTPIN (-6000 4450) SIG_NAME M_H_CPU1_SA_DQ<12>
J 0
(-5990 4460);
DISPLAY 0.659574 (-5990 4460);
PAINT MONO (-5990 4460);
DISPLAY INVISIBLE (-5990 4460);
FORCEPROP 1 LASTPIN (-6000 4450) BN 12
J 0
(-6012 4458);
DISPLAY 0.489362 (-6012 4458);
PAINT GREEN (-6012 4458);
FORCEPROP 2 LAST CDS_LIB mstr_standard
J 0
(-5950 4450);
DISPLAY 0.723404 (-5950 4450);
PAINT MONO (-5950 4450);
DISPLAY INVISIBLE (-5950 4450);
FORCEPROP 1 LAST BODY_TYPE PLUMBING
J 0
(-5950 4500);
DISPLAY 0.872340 (-5950 4500);
PAINT GREEN (-5950 4500);
DISPLAY INVISIBLE (-5950 4500);
FORCEPROP 1 LAST HDL_TAP TRUE
J 0
(-5625 4325);
DISPLAY 0.872340 (-5625 4325);
DISPLAY INVISIBLE (-5625 4325);
FORCEPROP 1 LAST PATH I105
J 0
(-5952 4450);
DISPLAY 0.872340 (-5952 4450);
PAINT GREEN (-5952 4450);
DISPLAY INVISIBLE (-5952 4450);
FORCEADD TAP..1
(-5950 4500);
FORCEPROP 3 LASTPIN (-6000 4500) SIG_NAME M_H_CPU1_SA_DQ<13>
J 0
(-5990 4510);
DISPLAY 0.659574 (-5990 4510);
PAINT MONO (-5990 4510);
DISPLAY INVISIBLE (-5990 4510);
FORCEPROP 1 LASTPIN (-6000 4500) BN 13
J 0
(-6012 4508);
DISPLAY 0.489362 (-6012 4508);
PAINT GREEN (-6012 4508);
FORCEPROP 2 LAST CDS_LIB mstr_standard
J 0
(-5950 4500);
DISPLAY 0.723404 (-5950 4500);
PAINT MONO (-5950 4500);
DISPLAY INVISIBLE (-5950 4500);
FORCEPROP 1 LAST BODY_TYPE PLUMBING
J 0
(-5950 4550);
DISPLAY 0.872340 (-5950 4550);
PAINT GREEN (-5950 4550);
DISPLAY INVISIBLE (-5950 4550);
FORCEPROP 1 LAST HDL_TAP TRUE
J 0
(-5625 4375);
DISPLAY 0.872340 (-5625 4375);
DISPLAY INVISIBLE (-5625 4375);
FORCEPROP 1 LAST PATH I106
J 0
(-5952 4500);
DISPLAY 0.872340 (-5952 4500);
PAINT GREEN (-5952 4500);
DISPLAY INVISIBLE (-5952 4500);
FORCEADD TAP..1
(-5950 4550);
FORCEPROP 3 LASTPIN (-6000 4550) SIG_NAME M_H_CPU1_SA_DQ<14>
J 0
(-5990 4560);
DISPLAY 0.659574 (-5990 4560);
PAINT MONO (-5990 4560);
DISPLAY INVISIBLE (-5990 4560);
FORCEPROP 1 LASTPIN (-6000 4550) BN 14
J 0
(-6012 4558);
DISPLAY 0.489362 (-6012 4558);
PAINT GREEN (-6012 4558);
FORCEPROP 2 LAST CDS_LIB mstr_standard
J 0
(-5950 4550);
DISPLAY 0.723404 (-5950 4550);
PAINT MONO (-5950 4550);
DISPLAY INVISIBLE (-5950 4550);
FORCEPROP 1 LAST BODY_TYPE PLUMBING
J 0
(-5950 4600);
DISPLAY 0.872340 (-5950 4600);
PAINT GREEN (-5950 4600);
DISPLAY INVISIBLE (-5950 4600);
FORCEPROP 1 LAST HDL_TAP TRUE
J 0
(-5625 4425);
DISPLAY 0.872340 (-5625 4425);
DISPLAY INVISIBLE (-5625 4425);
FORCEPROP 1 LAST PATH I107
J 0
(-5952 4550);
DISPLAY 0.872340 (-5952 4550);
PAINT GREEN (-5952 4550);
DISPLAY INVISIBLE (-5952 4550);
FORCEADD TAP..1
(-5950 4650);
FORCEPROP 3 LASTPIN (-6000 4650) SIG_NAME M_H_CPU1_SA_DQ<16>
J 0
(-5990 4660);
DISPLAY 0.659574 (-5990 4660);
PAINT MONO (-5990 4660);
DISPLAY INVISIBLE (-5990 4660);
FORCEPROP 1 LASTPIN (-6000 4650) BN 16
J 0
(-6012 4658);
DISPLAY 0.489362 (-6012 4658);
PAINT GREEN (-6012 4658);
FORCEPROP 2 LAST CDS_LIB mstr_standard
J 0
(-5950 4650);
DISPLAY 0.723404 (-5950 4650);
PAINT MONO (-5950 4650);
DISPLAY INVISIBLE (-5950 4650);
FORCEPROP 1 LAST BODY_TYPE PLUMBING
J 0
(-5950 4700);
DISPLAY 0.872340 (-5950 4700);
PAINT GREEN (-5950 4700);
DISPLAY INVISIBLE (-5950 4700);
FORCEPROP 1 LAST HDL_TAP TRUE
J 0
(-5625 4525);
DISPLAY 0.872340 (-5625 4525);
DISPLAY INVISIBLE (-5625 4525);
FORCEPROP 1 LAST PATH I108
J 0
(-5952 4650);
DISPLAY 0.872340 (-5952 4650);
PAINT GREEN (-5952 4650);
DISPLAY INVISIBLE (-5952 4650);
FORCEADD TAP..1
(-5950 4600);
FORCEPROP 3 LASTPIN (-6000 4600) SIG_NAME M_H_CPU1_SA_DQ<15>
J 0
(-5990 4610);
DISPLAY 0.659574 (-5990 4610);
PAINT MONO (-5990 4610);
DISPLAY INVISIBLE (-5990 4610);
FORCEPROP 1 LASTPIN (-6000 4600) BN 15
J 0
(-6012 4608);
DISPLAY 0.489362 (-6012 4608);
PAINT GREEN (-6012 4608);
FORCEPROP 2 LAST CDS_LIB mstr_standard
J 0
(-5950 4600);
DISPLAY 0.723404 (-5950 4600);
PAINT MONO (-5950 4600);
DISPLAY INVISIBLE (-5950 4600);
FORCEPROP 1 LAST BODY_TYPE PLUMBING
J 0
(-5950 4650);
DISPLAY 0.872340 (-5950 4650);
PAINT GREEN (-5950 4650);
DISPLAY INVISIBLE (-5950 4650);
FORCEPROP 1 LAST HDL_TAP TRUE
J 0
(-5625 4475);
DISPLAY 0.872340 (-5625 4475);
DISPLAY INVISIBLE (-5625 4475);
FORCEPROP 1 LAST PATH I109
J 0
(-5952 4600);
DISPLAY 0.872340 (-5952 4600);
PAINT GREEN (-5952 4600);
DISPLAY INVISIBLE (-5952 4600);
FORCEADD OFFPAGE..1
(-8250 4100);
FORCEPROP 2 LAST $XR0 44 
J 0
(-8501 4100);
DISPLAY 0.638298 (-8501 4100);
PAINT MONO (-8501 4100);
FORCEPROP 2 LAST CDS_LIB mstr_standard
J 0
(-8250 4100);
DISPLAY 0.808511 (-8250 4100);
DISPLAY INVISIBLE (-8250 4100);
FORCEPROP 1 LAST OFFPAGE TRUE
J 0
(-7925 3975);
DISPLAY 0.872340 (-7925 3975);
PAINT GREEN (-7925 3975);
DISPLAY INVISIBLE (-7925 3975);
FORCEPROP 1 LAST COMMENT_BODY TRUE
J 0
(-8125 4000);
DISPLAY 0.872340 (-8125 4000);
PAINT GREEN (-8125 4000);
DISPLAY INVISIBLE (-8125 4000);
FORCEPROP 2 LAST PATH I11
J 0
(-8450 4150);
DISPLAY 1.021277 (-8450 4150);
DISPLAY INVISIBLE (-8450 4150);
FORCEADD TAP..1
(-5950 4750);
FORCEPROP 3 LASTPIN (-6000 4750) SIG_NAME M_H_CPU1_SA_DQ<18>
J 0
(-5990 4760);
DISPLAY 0.659574 (-5990 4760);
PAINT MONO (-5990 4760);
DISPLAY INVISIBLE (-5990 4760);
FORCEPROP 1 LASTPIN (-6000 4750) BN 18
J 0
(-6012 4758);
DISPLAY 0.489362 (-6012 4758);
PAINT GREEN (-6012 4758);
FORCEPROP 2 LAST CDS_LIB mstr_standard
J 0
(-5950 4750);
DISPLAY 0.723404 (-5950 4750);
PAINT MONO (-5950 4750);
DISPLAY INVISIBLE (-5950 4750);
FORCEPROP 1 LAST BODY_TYPE PLUMBING
J 0
(-5950 4800);
DISPLAY 0.872340 (-5950 4800);
PAINT GREEN (-5950 4800);
DISPLAY INVISIBLE (-5950 4800);
FORCEPROP 1 LAST HDL_TAP TRUE
J 0
(-5625 4625);
DISPLAY 0.872340 (-5625 4625);
DISPLAY INVISIBLE (-5625 4625);
FORCEPROP 1 LAST PATH I110
J 0
(-5952 4750);
DISPLAY 0.872340 (-5952 4750);
PAINT GREEN (-5952 4750);
DISPLAY INVISIBLE (-5952 4750);
FORCEADD TAP..1
(-5950 4700);
FORCEPROP 3 LASTPIN (-6000 4700) SIG_NAME M_H_CPU1_SA_DQ<17>
J 0
(-5990 4710);
DISPLAY 0.659574 (-5990 4710);
PAINT MONO (-5990 4710);
DISPLAY INVISIBLE (-5990 4710);
FORCEPROP 1 LASTPIN (-6000 4700) BN 17
J 0
(-6012 4708);
DISPLAY 0.489362 (-6012 4708);
PAINT GREEN (-6012 4708);
FORCEPROP 2 LAST CDS_LIB mstr_standard
J 0
(-5950 4700);
DISPLAY 0.723404 (-5950 4700);
PAINT MONO (-5950 4700);
DISPLAY INVISIBLE (-5950 4700);
FORCEPROP 1 LAST BODY_TYPE PLUMBING
J 0
(-5950 4750);
DISPLAY 0.872340 (-5950 4750);
PAINT GREEN (-5950 4750);
DISPLAY INVISIBLE (-5950 4750);
FORCEPROP 1 LAST HDL_TAP TRUE
J 0
(-5625 4575);
DISPLAY 0.872340 (-5625 4575);
DISPLAY INVISIBLE (-5625 4575);
FORCEPROP 1 LAST PATH I111
J 0
(-5952 4700);
DISPLAY 0.872340 (-5952 4700);
PAINT GREEN (-5952 4700);
DISPLAY INVISIBLE (-5952 4700);
FORCEADD TAP..1
(-5950 4800);
FORCEPROP 3 LASTPIN (-6000 4800) SIG_NAME M_H_CPU1_SA_DQ<19>
J 0
(-5990 4810);
DISPLAY 0.659574 (-5990 4810);
PAINT MONO (-5990 4810);
DISPLAY INVISIBLE (-5990 4810);
FORCEPROP 1 LASTPIN (-6000 4800) BN 19
J 0
(-6012 4808);
DISPLAY 0.489362 (-6012 4808);
PAINT GREEN (-6012 4808);
FORCEPROP 2 LAST CDS_LIB mstr_standard
J 0
(-5950 4800);
DISPLAY 0.723404 (-5950 4800);
PAINT MONO (-5950 4800);
DISPLAY INVISIBLE (-5950 4800);
FORCEPROP 1 LAST BODY_TYPE PLUMBING
J 0
(-5950 4850);
DISPLAY 0.872340 (-5950 4850);
PAINT GREEN (-5950 4850);
DISPLAY INVISIBLE (-5950 4850);
FORCEPROP 1 LAST HDL_TAP TRUE
J 0
(-5625 4675);
DISPLAY 0.872340 (-5625 4675);
DISPLAY INVISIBLE (-5625 4675);
FORCEPROP 1 LAST PATH I112
J 0
(-5952 4800);
DISPLAY 0.872340 (-5952 4800);
PAINT GREEN (-5952 4800);
DISPLAY INVISIBLE (-5952 4800);
FORCEADD TAP..1
(-5950 4900);
FORCEPROP 3 LASTPIN (-6000 4900) SIG_NAME M_H_CPU1_SA_DQ<21>
J 0
(-5990 4910);
DISPLAY 0.659574 (-5990 4910);
PAINT MONO (-5990 4910);
DISPLAY INVISIBLE (-5990 4910);
FORCEPROP 1 LASTPIN (-6000 4900) BN 21
J 0
(-6012 4908);
DISPLAY 0.489362 (-6012 4908);
PAINT GREEN (-6012 4908);
FORCEPROP 2 LAST CDS_LIB mstr_standard
J 0
(-5950 4900);
DISPLAY 0.723404 (-5950 4900);
PAINT MONO (-5950 4900);
DISPLAY INVISIBLE (-5950 4900);
FORCEPROP 1 LAST BODY_TYPE PLUMBING
J 0
(-5950 4950);
DISPLAY 0.872340 (-5950 4950);
PAINT GREEN (-5950 4950);
DISPLAY INVISIBLE (-5950 4950);
FORCEPROP 1 LAST HDL_TAP TRUE
J 0
(-5625 4775);
DISPLAY 0.872340 (-5625 4775);
DISPLAY INVISIBLE (-5625 4775);
FORCEPROP 1 LAST PATH I113
J 0
(-5952 4900);
DISPLAY 0.872340 (-5952 4900);
PAINT GREEN (-5952 4900);
DISPLAY INVISIBLE (-5952 4900);
FORCEADD TAP..1
(-5950 4850);
FORCEPROP 3 LASTPIN (-6000 4850) SIG_NAME M_H_CPU1_SA_DQ<20>
J 0
(-5990 4860);
DISPLAY 0.659574 (-5990 4860);
PAINT MONO (-5990 4860);
DISPLAY INVISIBLE (-5990 4860);
FORCEPROP 1 LASTPIN (-6000 4850) BN 20
J 0
(-6012 4858);
DISPLAY 0.489362 (-6012 4858);
PAINT GREEN (-6012 4858);
FORCEPROP 2 LAST CDS_LIB mstr_standard
J 0
(-5950 4850);
DISPLAY 0.723404 (-5950 4850);
PAINT MONO (-5950 4850);
DISPLAY INVISIBLE (-5950 4850);
FORCEPROP 1 LAST BODY_TYPE PLUMBING
J 0
(-5950 4900);
DISPLAY 0.872340 (-5950 4900);
PAINT GREEN (-5950 4900);
DISPLAY INVISIBLE (-5950 4900);
FORCEPROP 1 LAST HDL_TAP TRUE
J 0
(-5625 4725);
DISPLAY 0.872340 (-5625 4725);
DISPLAY INVISIBLE (-5625 4725);
FORCEPROP 1 LAST PATH I114
J 0
(-5952 4850);
DISPLAY 0.872340 (-5952 4850);
PAINT GREEN (-5952 4850);
DISPLAY INVISIBLE (-5952 4850);
FORCEADD TAP..1
(-5950 4950);
FORCEPROP 3 LASTPIN (-6000 4950) SIG_NAME M_H_CPU1_SA_DQ<22>
J 0
(-5990 4960);
DISPLAY 0.659574 (-5990 4960);
PAINT MONO (-5990 4960);
DISPLAY INVISIBLE (-5990 4960);
FORCEPROP 1 LASTPIN (-6000 4950) BN 22
J 0
(-6012 4958);
DISPLAY 0.489362 (-6012 4958);
PAINT GREEN (-6012 4958);
FORCEPROP 2 LAST CDS_LIB mstr_standard
J 0
(-5950 4950);
DISPLAY 0.723404 (-5950 4950);
PAINT MONO (-5950 4950);
DISPLAY INVISIBLE (-5950 4950);
FORCEPROP 1 LAST BODY_TYPE PLUMBING
J 0
(-5950 5000);
DISPLAY 0.872340 (-5950 5000);
PAINT GREEN (-5950 5000);
DISPLAY INVISIBLE (-5950 5000);
FORCEPROP 1 LAST HDL_TAP TRUE
J 0
(-5625 4825);
DISPLAY 0.872340 (-5625 4825);
DISPLAY INVISIBLE (-5625 4825);
FORCEPROP 1 LAST PATH I115
J 0
(-5952 4950);
DISPLAY 0.872340 (-5952 4950);
PAINT GREEN (-5952 4950);
DISPLAY INVISIBLE (-5952 4950);
FORCEADD TAP..1
(-5950 5000);
FORCEPROP 3 LASTPIN (-6000 5000) SIG_NAME M_H_CPU1_SA_DQ<23>
J 0
(-5990 5010);
DISPLAY 0.659574 (-5990 5010);
PAINT MONO (-5990 5010);
DISPLAY INVISIBLE (-5990 5010);
FORCEPROP 1 LASTPIN (-6000 5000) BN 23
J 0
(-6012 5008);
DISPLAY 0.489362 (-6012 5008);
PAINT GREEN (-6012 5008);
FORCEPROP 2 LAST CDS_LIB mstr_standard
J 0
(-5950 5000);
DISPLAY 0.723404 (-5950 5000);
PAINT MONO (-5950 5000);
DISPLAY INVISIBLE (-5950 5000);
FORCEPROP 1 LAST BODY_TYPE PLUMBING
J 0
(-5950 5050);
DISPLAY 0.872340 (-5950 5050);
PAINT GREEN (-5950 5050);
DISPLAY INVISIBLE (-5950 5050);
FORCEPROP 1 LAST HDL_TAP TRUE
J 0
(-5625 4875);
DISPLAY 0.872340 (-5625 4875);
DISPLAY INVISIBLE (-5625 4875);
FORCEPROP 1 LAST PATH I116
J 0
(-5952 5000);
DISPLAY 0.872340 (-5952 5000);
PAINT GREEN (-5952 5000);
DISPLAY INVISIBLE (-5952 5000);
FORCEADD TAP..1
(-5950 5100);
FORCEPROP 3 LASTPIN (-6000 5100) SIG_NAME M_H_CPU1_SA_DQ<25>
J 0
(-5990 5110);
DISPLAY 0.659574 (-5990 5110);
PAINT MONO (-5990 5110);
DISPLAY INVISIBLE (-5990 5110);
FORCEPROP 1 LASTPIN (-6000 5100) BN 25
J 0
(-6012 5108);
DISPLAY 0.489362 (-6012 5108);
PAINT GREEN (-6012 5108);
FORCEPROP 2 LAST CDS_LIB mstr_standard
J 0
(-5950 5100);
DISPLAY 0.723404 (-5950 5100);
PAINT MONO (-5950 5100);
DISPLAY INVISIBLE (-5950 5100);
FORCEPROP 1 LAST BODY_TYPE PLUMBING
J 0
(-5950 5150);
DISPLAY 0.872340 (-5950 5150);
PAINT GREEN (-5950 5150);
DISPLAY INVISIBLE (-5950 5150);
FORCEPROP 1 LAST HDL_TAP TRUE
J 0
(-5625 4975);
DISPLAY 0.872340 (-5625 4975);
DISPLAY INVISIBLE (-5625 4975);
FORCEPROP 1 LAST PATH I117
J 0
(-5952 5100);
DISPLAY 0.872340 (-5952 5100);
PAINT GREEN (-5952 5100);
DISPLAY INVISIBLE (-5952 5100);
FORCEADD TAP..1
(-5950 5050);
FORCEPROP 3 LASTPIN (-6000 5050) SIG_NAME M_H_CPU1_SA_DQ<24>
J 0
(-5990 5060);
DISPLAY 0.659574 (-5990 5060);
PAINT MONO (-5990 5060);
DISPLAY INVISIBLE (-5990 5060);
FORCEPROP 1 LASTPIN (-6000 5050) BN 24
J 0
(-6012 5058);
DISPLAY 0.489362 (-6012 5058);
PAINT GREEN (-6012 5058);
FORCEPROP 2 LAST CDS_LIB mstr_standard
J 0
(-5950 5050);
DISPLAY 0.723404 (-5950 5050);
PAINT MONO (-5950 5050);
DISPLAY INVISIBLE (-5950 5050);
FORCEPROP 1 LAST BODY_TYPE PLUMBING
J 0
(-5950 5100);
DISPLAY 0.872340 (-5950 5100);
PAINT GREEN (-5950 5100);
DISPLAY INVISIBLE (-5950 5100);
FORCEPROP 1 LAST HDL_TAP TRUE
J 0
(-5625 4925);
DISPLAY 0.872340 (-5625 4925);
DISPLAY INVISIBLE (-5625 4925);
FORCEPROP 1 LAST PATH I118
J 0
(-5952 5050);
DISPLAY 0.872340 (-5952 5050);
PAINT GREEN (-5952 5050);
DISPLAY INVISIBLE (-5952 5050);
FORCEADD TAP..1
(-5950 5150);
FORCEPROP 3 LASTPIN (-6000 5150) SIG_NAME M_H_CPU1_SA_DQ<26>
J 0
(-5990 5160);
DISPLAY 0.659574 (-5990 5160);
PAINT MONO (-5990 5160);
DISPLAY INVISIBLE (-5990 5160);
FORCEPROP 1 LASTPIN (-6000 5150) BN 26
J 0
(-6012 5158);
DISPLAY 0.489362 (-6012 5158);
PAINT GREEN (-6012 5158);
FORCEPROP 2 LAST CDS_LIB mstr_standard
J 0
(-5950 5150);
DISPLAY 0.723404 (-5950 5150);
PAINT MONO (-5950 5150);
DISPLAY INVISIBLE (-5950 5150);
FORCEPROP 1 LAST BODY_TYPE PLUMBING
J 0
(-5950 5200);
DISPLAY 0.872340 (-5950 5200);
PAINT GREEN (-5950 5200);
DISPLAY INVISIBLE (-5950 5200);
FORCEPROP 1 LAST HDL_TAP TRUE
J 0
(-5625 5025);
DISPLAY 0.872340 (-5625 5025);
DISPLAY INVISIBLE (-5625 5025);
FORCEPROP 1 LAST PATH I119
J 0
(-5952 5150);
DISPLAY 0.872340 (-5952 5150);
PAINT GREEN (-5952 5150);
DISPLAY INVISIBLE (-5952 5150);
FORCEADD OFFPAGE..6
(-8250 4050);
FORCEPROP 2 LAST $XR0 44 
J 0
(-8529 4050);
DISPLAY 0.638298 (-8529 4050);
PAINT MONO (-8529 4050);
FORCEPROP 2 LAST CDS_LIB mstr_standard
J 0
(-8250 4050);
DISPLAY 0.723404 (-8250 4050);
PAINT MONO (-8250 4050);
DISPLAY INVISIBLE (-8250 4050);
FORCEPROP 1 LAST OFFPAGE TRUE
J 0
(-7925 3925);
DISPLAY 0.872340 (-7925 3925);
PAINT GREEN (-7925 3925);
DISPLAY INVISIBLE (-7925 3925);
FORCEPROP 1 LAST COMMENT_BODY TRUE
J 0
(-8150 3975);
DISPLAY 0.872340 (-8150 3975);
PAINT GREEN (-8150 3975);
DISPLAY INVISIBLE (-8150 3975);
FORCEPROP 2 LAST PATH I12
J 0
(-8525 4100);
DISPLAY 1.021277 (-8525 4100);
DISPLAY INVISIBLE (-8525 4100);
FORCEADD TAP..1
(-5950 5300);
FORCEPROP 3 LASTPIN (-6000 5300) SIG_NAME M_H_CPU1_SA_DQ<29>
J 0
(-5990 5310);
DISPLAY 0.659574 (-5990 5310);
PAINT MONO (-5990 5310);
DISPLAY INVISIBLE (-5990 5310);
FORCEPROP 1 LASTPIN (-6000 5300) BN 29
J 0
(-6012 5308);
DISPLAY 0.489362 (-6012 5308);
PAINT GREEN (-6012 5308);
FORCEPROP 2 LAST CDS_LIB mstr_standard
J 0
(-5950 5300);
DISPLAY 0.723404 (-5950 5300);
PAINT MONO (-5950 5300);
DISPLAY INVISIBLE (-5950 5300);
FORCEPROP 1 LAST BODY_TYPE PLUMBING
J 0
(-5950 5350);
DISPLAY 0.872340 (-5950 5350);
PAINT GREEN (-5950 5350);
DISPLAY INVISIBLE (-5950 5350);
FORCEPROP 1 LAST HDL_TAP TRUE
J 0
(-5625 5175);
DISPLAY 0.872340 (-5625 5175);
DISPLAY INVISIBLE (-5625 5175);
FORCEPROP 1 LAST PATH I120
J 0
(-5952 5300);
DISPLAY 0.872340 (-5952 5300);
PAINT GREEN (-5952 5300);
DISPLAY INVISIBLE (-5952 5300);
FORCEADD TAP..1
(-5950 5250);
FORCEPROP 3 LASTPIN (-6000 5250) SIG_NAME M_H_CPU1_SA_DQ<28>
J 0
(-5990 5260);
DISPLAY 0.659574 (-5990 5260);
PAINT MONO (-5990 5260);
DISPLAY INVISIBLE (-5990 5260);
FORCEPROP 1 LASTPIN (-6000 5250) BN 28
J 0
(-6012 5258);
DISPLAY 0.489362 (-6012 5258);
PAINT GREEN (-6012 5258);
FORCEPROP 2 LAST CDS_LIB mstr_standard
J 0
(-5950 5250);
DISPLAY 0.723404 (-5950 5250);
PAINT MONO (-5950 5250);
DISPLAY INVISIBLE (-5950 5250);
FORCEPROP 1 LAST BODY_TYPE PLUMBING
J 0
(-5950 5300);
DISPLAY 0.872340 (-5950 5300);
PAINT GREEN (-5950 5300);
DISPLAY INVISIBLE (-5950 5300);
FORCEPROP 1 LAST HDL_TAP TRUE
J 0
(-5625 5125);
DISPLAY 0.872340 (-5625 5125);
DISPLAY INVISIBLE (-5625 5125);
FORCEPROP 1 LAST PATH I121
J 0
(-5952 5250);
DISPLAY 0.872340 (-5952 5250);
PAINT GREEN (-5952 5250);
DISPLAY INVISIBLE (-5952 5250);
FORCEADD TAP..1
(-5950 5200);
FORCEPROP 3 LASTPIN (-6000 5200) SIG_NAME M_H_CPU1_SA_DQ<27>
J 0
(-5990 5210);
DISPLAY 0.659574 (-5990 5210);
PAINT MONO (-5990 5210);
DISPLAY INVISIBLE (-5990 5210);
FORCEPROP 1 LASTPIN (-6000 5200) BN 27
J 0
(-6012 5208);
DISPLAY 0.489362 (-6012 5208);
PAINT GREEN (-6012 5208);
FORCEPROP 2 LAST CDS_LIB mstr_standard
J 0
(-5950 5200);
DISPLAY 0.723404 (-5950 5200);
PAINT MONO (-5950 5200);
DISPLAY INVISIBLE (-5950 5200);
FORCEPROP 1 LAST BODY_TYPE PLUMBING
J 0
(-5950 5250);
DISPLAY 0.872340 (-5950 5250);
PAINT GREEN (-5950 5250);
DISPLAY INVISIBLE (-5950 5250);
FORCEPROP 1 LAST HDL_TAP TRUE
J 0
(-5625 5075);
DISPLAY 0.872340 (-5625 5075);
DISPLAY INVISIBLE (-5625 5075);
FORCEPROP 1 LAST PATH I122
J 0
(-5952 5200);
DISPLAY 0.872340 (-5952 5200);
PAINT GREEN (-5952 5200);
DISPLAY INVISIBLE (-5952 5200);
FORCEADD TAP..1
(-5950 5350);
FORCEPROP 3 LASTPIN (-6000 5350) SIG_NAME M_H_CPU1_SA_DQ<30>
J 0
(-5990 5360);
DISPLAY 0.659574 (-5990 5360);
PAINT MONO (-5990 5360);
DISPLAY INVISIBLE (-5990 5360);
FORCEPROP 1 LASTPIN (-6000 5350) BN 30
J 0
(-6012 5358);
DISPLAY 0.489362 (-6012 5358);
PAINT GREEN (-6012 5358);
FORCEPROP 2 LAST CDS_LIB mstr_standard
J 0
(-5950 5350);
DISPLAY 0.723404 (-5950 5350);
PAINT MONO (-5950 5350);
DISPLAY INVISIBLE (-5950 5350);
FORCEPROP 1 LAST BODY_TYPE PLUMBING
J 0
(-5950 5400);
DISPLAY 0.872340 (-5950 5400);
PAINT GREEN (-5950 5400);
DISPLAY INVISIBLE (-5950 5400);
FORCEPROP 1 LAST HDL_TAP TRUE
J 0
(-5625 5225);
DISPLAY 0.872340 (-5625 5225);
DISPLAY INVISIBLE (-5625 5225);
FORCEPROP 1 LAST PATH I123
J 0
(-5952 5350);
DISPLAY 0.872340 (-5952 5350);
PAINT GREEN (-5952 5350);
DISPLAY INVISIBLE (-5952 5350);
FORCEADD TAP..1
(-5950 5400);
FORCEPROP 3 LASTPIN (-6000 5400) SIG_NAME M_H_CPU1_SA_DQ<31>
J 0
(-5990 5410);
DISPLAY 0.659574 (-5990 5410);
PAINT MONO (-5990 5410);
DISPLAY INVISIBLE (-5990 5410);
FORCEPROP 1 LASTPIN (-6000 5400) BN 31
J 0
(-6012 5408);
DISPLAY 0.489362 (-6012 5408);
PAINT GREEN (-6012 5408);
FORCEPROP 2 LAST CDS_LIB mstr_standard
J 0
(-5950 5400);
DISPLAY 0.723404 (-5950 5400);
PAINT MONO (-5950 5400);
DISPLAY INVISIBLE (-5950 5400);
FORCEPROP 1 LAST BODY_TYPE PLUMBING
J 0
(-5950 5450);
DISPLAY 0.872340 (-5950 5450);
PAINT GREEN (-5950 5450);
DISPLAY INVISIBLE (-5950 5450);
FORCEPROP 1 LAST HDL_TAP TRUE
J 0
(-5625 5275);
DISPLAY 0.872340 (-5625 5275);
DISPLAY INVISIBLE (-5625 5275);
FORCEPROP 1 LAST PATH I124
J 0
(-5952 5400);
DISPLAY 0.872340 (-5952 5400);
PAINT GREEN (-5952 5400);
DISPLAY INVISIBLE (-5952 5400);
FORCEADD OFFPAGE..3
(-5325 5450);
FORCEPROP 2 LAST $XR0 44 
J 0
(-5111 5450);
DISPLAY 0.638298 (-5111 5450);
PAINT MONO (-5111 5450);
FORCEPROP 2 LAST CDS_LIB mstr_standard
J 0
(-5325 5450);
DISPLAY 0.723404 (-5325 5450);
PAINT MONO (-5325 5450);
DISPLAY INVISIBLE (-5325 5450);
FORCEPROP 1 LAST OFFPAGE TRUE
J 0
(-5000 5325);
DISPLAY 0.872340 (-5000 5325);
PAINT GREEN (-5000 5325);
DISPLAY INVISIBLE (-5000 5325);
FORCEPROP 1 LAST COMMENT_BODY TRUE
J 0
(-5375 5350);
DISPLAY 0.872340 (-5375 5350);
PAINT GREEN (-5375 5350);
DISPLAY INVISIBLE (-5375 5350);
FORCEPROP 2 LAST PATH I125
J 0
(-5100 5500);
DISPLAY 1.021277 (-5100 5500);
DISPLAY INVISIBLE (-5100 5500);
FORCEADD OFFPAGE..5
(-7150 1250);
FORCEPROP 2 LAST $XR0 105 
J 0
(-7405 1250);
DISPLAY 0.638298 (-7405 1250);
PAINT MONO (-7405 1250);
FORCEPROP 2 LAST BOM_COST MEM
J 0
(-7225 1325);
DISPLAY 0.808511 (-7225 1325);
DISPLAY INVISIBLE (-7225 1325);
FORCEPROP 2 LAST CDS_LIB mstr_standard
J 0
(-7150 1250);
DISPLAY 0.808511 (-7150 1250);
DISPLAY INVISIBLE (-7150 1250);
FORCEPROP 1 LAST OFFPAGE TRUE
J 0
(-6825 1125);
DISPLAY 0.872340 (-6825 1125);
PAINT GREEN (-6825 1125);
DISPLAY INVISIBLE (-6825 1125);
FORCEPROP 1 LAST COMMENT_BODY TRUE
J 0
(-7050 1175);
DISPLAY 0.872340 (-7050 1175);
PAINT GREEN (-7050 1175);
DISPLAY INVISIBLE (-7050 1175);
FORCEPROP 2 LAST PATH I126
J 0
(-7400 1300);
DISPLAY 1.021277 (-7400 1300);
DISPLAY INVISIBLE (-7400 1300);
FORCEADD GND..1
(-6375 850);
FORCEPROP 3 LASTPIN (-6375 900) SIG_NAME GND\g
J 0
(-6365 910);
DISPLAY 0.659574 (-6365 910);
PAINT MONO (-6365 910);
DISPLAY INVISIBLE (-6365 910);
FORCEPROP 1 LAST SIZE 1B
J 0
(-6300 800);
DISPLAY 0.851064 (-6300 800);
PAINT GREEN (-6300 800);
DISPLAY INVISIBLE (-6300 800);
FORCEPROP 2 LAST CDS_LIB mstr_symbols
J 0
(-6375 850);
DISPLAY 0.808511 (-6375 850);
DISPLAY INVISIBLE (-6375 850);
FORCEPROP 2 LAST BOM_COST MEM
J 0
(-6475 925);
DISPLAY 0.808511 (-6475 925);
DISPLAY INVISIBLE (-6475 925);
FORCEPROP 1 LAST VOLTAGE 0.0
J 0
(-6420 807);
DISPLAY 0.723404 (-6420 807);
PAINT SKYBLUE (-6420 807);
DISPLAY INVISIBLE (-6420 807);
FORCEPROP 1 LAST BODY_TYPE PLUMBING
J 0
(-6420 807);
DISPLAY 0.340426 (-6420 807);
PAINT GREEN (-6420 807);
DISPLAY INVISIBLE (-6420 807);
FORCEPROP 1 LAST HDL_POWER GND
J 0
(-6375 1000);
DISPLAY 0.851064 (-6375 1000);
PAINT GREEN (-6375 1000);
DISPLAY INVISIBLE (-6375 1000);
FORCEPROP 1 LAST PATH I127
J 0
(-6300 850);
DISPLAY 0.872340 (-6300 850);
PAINT AQUA (-6300 850);
DISPLAY INVISIBLE (-6300 850);
FORCEADD Q_RES..2
(-6375 1075);
FORCEPROP 1 LAST LOCATION R774
J 0
(-6330 1200);
DISPLAY 0.489362 (-6330 1200);
PAINT SKYBLUE (-6330 1200);
FORCEPROP 0 LAST $SEC 1
J 0
(-6325 1250);
DISPLAY 0.680851 (-6325 1250);
PAINT MONO (-6325 1250);
DISPLAY INVISIBLE (-6325 1250);
FORCEPROP 0 LAST CDS_SEC 1
J 0
(-6325 1250);
DISPLAY 1.021277 (-6325 1250);
DISPLAY INVISIBLE (-6325 1250);
FORCEPROP 1 LASTPIN (-6375 1175) $PN 1
J 0
(-6370 1137);
DISPLAY 0.489362 (-6370 1137);
PAINT MONO (-6370 1137);
FORCEPROP 1 LASTPIN (-6375 975) $PN 2
J 0
(-6370 985);
DISPLAY 0.489362 (-6370 985);
PAINT MONO (-6370 985);
FORCEPROP 1 LAST WATTAGE 1/16W
J 0
(-6335 1050);
DISPLAY 0.489362 (-6335 1050);
PAINT SKYBLUE (-6335 1050);
FORCEPROP 1 LAST MATERIAL CHIP
J 0
(-6335 1000);
DISPLAY 0.489362 (-6335 1000);
PAINT SKYBLUE (-6335 1000);
FORCEPROP 1 LAST TOLERANCE 1%
J 0
(-6330 1100);
DISPLAY 0.489362 (-6330 1100);
PAINT SKYBLUE (-6330 1100);
FORCEPROP 1 LAST VALUE 15.4K
J 0
(-6330 1150);
DISPLAY 0.489362 (-6330 1150);
PAINT SKYBLUE (-6330 1150);
FORCEPROP 1 LAST PACK_TYPE 0402LF
J 0
(-6335 900);
DISPLAY 0.489362 (-6335 900);
PAINT SKYBLUE (-6335 900);
FORCEPROP 2 LAST CDS_LIB pure_quanta
J 0
(-6375 1075);
DISPLAY INVISIBLE (-6375 1075);
FORCEPROP 1 LAST PATH I128
J 0
(-6325 1250);
DISPLAY 0.978723 (-6325 1250);
PAINT WHITE (-6325 1250);
DISPLAY INVISIBLE (-6325 1250);
FORCEPROP 1 LAST PART_NUMBER CS31542FB02
J 0
(-6335 950);
DISPLAY 0.489362 (-6335 950);
PAINT SKYBLUE (-6335 950);
DISPLAY INVISIBLE (-6335 950);
FORCEADD OFFPAGE..1
(-8250 4150);
FORCEPROP 2 LAST $XR0 44 
J 0
(-8501 4150);
DISPLAY 0.638298 (-8501 4150);
PAINT MONO (-8501 4150);
FORCEPROP 2 LAST CDS_LIB mstr_standard
J 0
(-8250 4150);
DISPLAY 0.723404 (-8250 4150);
PAINT MONO (-8250 4150);
DISPLAY INVISIBLE (-8250 4150);
FORCEPROP 1 LAST OFFPAGE TRUE
J 0
(-7925 4025);
DISPLAY 0.872340 (-7925 4025);
PAINT GREEN (-7925 4025);
DISPLAY INVISIBLE (-7925 4025);
FORCEPROP 1 LAST COMMENT_BODY TRUE
J 0
(-8125 4050);
DISPLAY 0.872340 (-8125 4050);
PAINT GREEN (-8125 4050);
DISPLAY INVISIBLE (-8125 4050);
FORCEPROP 2 LAST PATH I13
J 0
(-8450 4200);
DISPLAY 1.021277 (-8450 4200);
DISPLAY INVISIBLE (-8450 4200);
FORCEADD OFFPAGE..1
(-8250 4250);
FORCEPROP 2 LAST $XR0 44 
J 0
(-8501 4250);
DISPLAY 0.638298 (-8501 4250);
PAINT MONO (-8501 4250);
FORCEPROP 2 LAST CDS_LIB mstr_standard
J 0
(-8250 4250);
DISPLAY 0.808511 (-8250 4250);
DISPLAY INVISIBLE (-8250 4250);
FORCEPROP 1 LAST OFFPAGE TRUE
J 0
(-7925 4125);
DISPLAY 0.872340 (-7925 4125);
PAINT GREEN (-7925 4125);
DISPLAY INVISIBLE (-7925 4125);
FORCEPROP 1 LAST COMMENT_BODY TRUE
J 0
(-8125 4150);
DISPLAY 0.872340 (-8125 4150);
PAINT GREEN (-8125 4150);
DISPLAY INVISIBLE (-8125 4150);
FORCEPROP 2 LAST PATH I14
J 0
(-8450 4300);
DISPLAY 1.021277 (-8450 4300);
DISPLAY INVISIBLE (-8450 4300);
FORCEADD GND..1
(-2125 1875);
FORCEPROP 3 LASTPIN (-2125 1925) SIG_NAME GND\g
J 0
(-2115 1935);
DISPLAY 0.659574 (-2115 1935);
PAINT MONO (-2115 1935);
DISPLAY INVISIBLE (-2115 1935);
FORCEPROP 1 LAST SIZE 1B
J 0
(-2050 1825);
DISPLAY 0.851064 (-2050 1825);
PAINT GREEN (-2050 1825);
DISPLAY INVISIBLE (-2050 1825);
FORCEPROP 2 LAST CDS_LIB mstr_symbols
J 0
(-2125 1875);
DISPLAY 0.723404 (-2125 1875);
DISPLAY INVISIBLE (-2125 1875);
FORCEPROP 1 LAST VOLTAGE 0.0
J 0
(-2170 1832);
DISPLAY 0.723404 (-2170 1832);
PAINT SKYBLUE (-2170 1832);
DISPLAY INVISIBLE (-2170 1832);
FORCEPROP 1 LAST BODY_TYPE PLUMBING
J 0
(-2170 1832);
DISPLAY 0.340426 (-2170 1832);
PAINT GREEN (-2170 1832);
DISPLAY INVISIBLE (-2170 1832);
FORCEPROP 1 LAST HDL_POWER GND
J 0
(-2125 2025);
DISPLAY 0.851064 (-2125 2025);
PAINT GREEN (-2125 2025);
DISPLAY INVISIBLE (-2125 2025);
FORCEPROP 1 LAST PATH I140
J 0
(-2050 1875);
DISPLAY 0.872340 (-2050 1875);
PAINT AQUA (-2050 1875);
DISPLAY INVISIBLE (-2050 1875);
FORCEADD GND..1
(-325 1650);
FORCEPROP 3 LASTPIN (-325 1700) SIG_NAME GND\g
J 0
(-315 1710);
DISPLAY 0.659574 (-315 1710);
PAINT MONO (-315 1710);
DISPLAY INVISIBLE (-315 1710);
FORCEPROP 1 LAST SIZE 1B
J 0
(-250 1600);
DISPLAY 0.851064 (-250 1600);
PAINT GREEN (-250 1600);
DISPLAY INVISIBLE (-250 1600);
FORCEPROP 2 LAST CDS_LIB mstr_symbols
J 0
(-325 1650);
DISPLAY 0.723404 (-325 1650);
DISPLAY INVISIBLE (-325 1650);
FORCEPROP 1 LAST VOLTAGE 0.0
J 0
(-370 1607);
DISPLAY 0.723404 (-370 1607);
PAINT SKYBLUE (-370 1607);
DISPLAY INVISIBLE (-370 1607);
FORCEPROP 1 LAST BODY_TYPE PLUMBING
J 0
(-370 1607);
DISPLAY 0.340426 (-370 1607);
PAINT GREEN (-370 1607);
DISPLAY INVISIBLE (-370 1607);
FORCEPROP 1 LAST HDL_POWER GND
J 0
(-325 1800);
DISPLAY 0.851064 (-325 1800);
PAINT GREEN (-325 1800);
DISPLAY INVISIBLE (-325 1800);
FORCEPROP 1 LAST PATH I141
J 0
(-250 1650);
DISPLAY 0.872340 (-250 1650);
PAINT AQUA (-250 1650);
DISPLAY INVISIBLE (-250 1650);
FORCEADD OFFPAGE..1
(-8250 4300);
FORCEPROP 2 LAST $XR0 44 
J 0
(-8501 4300);
DISPLAY 0.638298 (-8501 4300);
PAINT MONO (-8501 4300);
FORCEPROP 2 LAST CDS_LIB mstr_standard
J 0
(-8250 4300);
DISPLAY 0.723404 (-8250 4300);
PAINT MONO (-8250 4300);
DISPLAY INVISIBLE (-8250 4300);
FORCEPROP 1 LAST OFFPAGE TRUE
J 0
(-7925 4175);
DISPLAY 0.872340 (-7925 4175);
PAINT GREEN (-7925 4175);
DISPLAY INVISIBLE (-7925 4175);
FORCEPROP 1 LAST COMMENT_BODY TRUE
J 0
(-8125 4200);
DISPLAY 0.872340 (-8125 4200);
PAINT GREEN (-8125 4200);
DISPLAY INVISIBLE (-8125 4200);
FORCEPROP 2 LAST PATH I15
J 0
(-8450 4350);
DISPLAY 1.021277 (-8450 4350);
DISPLAY INVISIBLE (-8450 4350);
FORCEADD OFFPAGE..1
(-8250 4400);
FORCEPROP 2 LAST $XR0 44 
J 0
(-8501 4400);
DISPLAY 0.638298 (-8501 4400);
PAINT MONO (-8501 4400);
FORCEPROP 2 LAST CDS_LIB mstr_standard
J 0
(-8250 4400);
DISPLAY 0.808511 (-8250 4400);
DISPLAY INVISIBLE (-8250 4400);
FORCEPROP 1 LAST OFFPAGE TRUE
J 0
(-7925 4275);
DISPLAY 0.872340 (-7925 4275);
PAINT GREEN (-7925 4275);
DISPLAY INVISIBLE (-7925 4275);
FORCEPROP 1 LAST COMMENT_BODY TRUE
J 0
(-8125 4300);
DISPLAY 0.872340 (-8125 4300);
PAINT GREEN (-8125 4300);
DISPLAY INVISIBLE (-8125 4300);
FORCEPROP 2 LAST PATH I16
J 0
(-8450 4450);
DISPLAY 1.021277 (-8450 4450);
DISPLAY INVISIBLE (-8450 4450);
FORCEADD OFFPAGE..1
(-8250 4550);
FORCEPROP 2 LAST $XR0 44 
J 0
(-8501 4550);
DISPLAY 0.638298 (-8501 4550);
PAINT MONO (-8501 4550);
FORCEPROP 2 LAST CDS_LIB mstr_standard
J 0
(-8250 4550);
DISPLAY 0.808511 (-8250 4550);
DISPLAY INVISIBLE (-8250 4550);
FORCEPROP 1 LAST OFFPAGE TRUE
J 0
(-7925 4425);
DISPLAY 0.872340 (-7925 4425);
PAINT GREEN (-7925 4425);
DISPLAY INVISIBLE (-7925 4425);
FORCEPROP 1 LAST COMMENT_BODY TRUE
J 0
(-8125 4450);
DISPLAY 0.872340 (-8125 4450);
PAINT GREEN (-8125 4450);
DISPLAY INVISIBLE (-8125 4450);
FORCEPROP 2 LAST PATH I17
J 0
(-8450 4600);
DISPLAY 1.021277 (-8450 4600);
DISPLAY INVISIBLE (-8450 4600);
FORCEADD SCONN288_DDR506112002KQ..3
(-1225 3650);
FORCEPROP 1 LAST LOCATION J27
J 0
(-1675 5625);
DISPLAY 0.468085 (-1675 5625);
PAINT SKYBLUE (-1675 5625);
FORCEPROP 0 LAST $SEC 3
J 0
(-1675 5775);
DISPLAY 0.680851 (-1675 5775);
PAINT MONO (-1675 5775);
DISPLAY INVISIBLE (-1675 5775);
FORCEPROP 2 LAST CDS_SEC 3
J 0
(-1675 5775);
DISPLAY 1.021277 (-1675 5775);
DISPLAY INVISIBLE (-1675 5775);
FORCEPROP 0 LASTPIN (-625 2050) $PN G1
J 0
(-615 2060);
DISPLAY 0.680851 (-615 2060);
PAINT MONO (-615 2060);
FORCEPROP 0 LASTPIN (-625 2000) $PN G2
J 0
(-615 2010);
DISPLAY 0.680851 (-615 2010);
PAINT MONO (-615 2010);
FORCEPROP 0 LASTPIN (-625 1950) $PN G3
J 0
(-615 1960);
DISPLAY 0.680851 (-615 1960);
PAINT MONO (-615 1960);
FORCEPROP 0 LASTPIN (-1825 5200) $PN 1
J 2
(-1835 5210);
DISPLAY 0.680851 (-1835 5210);
PAINT MONO (-1835 5210);
FORCEPROP 0 LASTPIN (-1825 5250) $PN 145
J 2
(-1835 5260);
DISPLAY 0.680851 (-1835 5260);
PAINT MONO (-1835 5260);
FORCEPROP 0 LASTPIN (-1825 5300) $PN 146
J 2
(-1835 5310);
DISPLAY 0.680851 (-1835 5310);
PAINT MONO (-1835 5310);
FORCEPROP 0 LASTPIN (-625 2150) $PN 6
J 0
(-615 2160);
DISPLAY 0.680851 (-615 2160);
PAINT MONO (-615 2160);
FORCEPROP 0 LASTPIN (-625 2200) $PN 8
J 0
(-615 2210);
DISPLAY 0.680851 (-615 2210);
PAINT MONO (-615 2210);
FORCEPROP 0 LASTPIN (-625 2250) $PN 10
J 0
(-615 2260);
DISPLAY 0.680851 (-615 2260);
PAINT MONO (-615 2260);
FORCEPROP 0 LASTPIN (-625 2300) $PN 13
J 0
(-615 2310);
DISPLAY 0.680851 (-615 2310);
PAINT MONO (-615 2310);
FORCEPROP 0 LASTPIN (-625 2350) $PN 15
J 0
(-615 2360);
DISPLAY 0.680851 (-615 2360);
PAINT MONO (-615 2360);
FORCEPROP 0 LASTPIN (-625 2400) $PN 17
J 0
(-615 2410);
DISPLAY 0.680851 (-615 2410);
PAINT MONO (-615 2410);
FORCEPROP 0 LASTPIN (-625 2450) $PN 19
J 0
(-615 2460);
DISPLAY 0.680851 (-615 2460);
PAINT MONO (-615 2460);
FORCEPROP 0 LASTPIN (-625 2500) $PN 21
J 0
(-615 2510);
DISPLAY 0.680851 (-615 2510);
PAINT MONO (-615 2510);
FORCEPROP 0 LASTPIN (-625 2550) $PN 24
J 0
(-615 2560);
DISPLAY 0.680851 (-615 2560);
PAINT MONO (-615 2560);
FORCEPROP 0 LASTPIN (-625 2600) $PN 26
J 0
(-615 2610);
DISPLAY 0.680851 (-615 2610);
PAINT MONO (-615 2610);
FORCEPROP 0 LASTPIN (-625 2650) $PN 28
J 0
(-615 2660);
DISPLAY 0.680851 (-615 2660);
PAINT MONO (-615 2660);
FORCEPROP 0 LASTPIN (-625 2700) $PN 30
J 0
(-615 2710);
DISPLAY 0.680851 (-615 2710);
PAINT MONO (-615 2710);
FORCEPROP 0 LASTPIN (-625 2750) $PN 32
J 0
(-615 2760);
DISPLAY 0.680851 (-615 2760);
PAINT MONO (-615 2760);
FORCEPROP 0 LASTPIN (-625 2800) $PN 35
J 0
(-615 2810);
DISPLAY 0.680851 (-615 2810);
PAINT MONO (-615 2810);
FORCEPROP 0 LASTPIN (-625 2850) $PN 37
J 0
(-615 2860);
DISPLAY 0.680851 (-615 2860);
PAINT MONO (-615 2860);
FORCEPROP 0 LASTPIN (-625 2900) $PN 39
J 0
(-615 2910);
DISPLAY 0.680851 (-615 2910);
PAINT MONO (-615 2910);
FORCEPROP 0 LASTPIN (-625 2950) $PN 41
J 0
(-615 2960);
DISPLAY 0.680851 (-615 2960);
PAINT MONO (-615 2960);
FORCEPROP 0 LASTPIN (-625 3000) $PN 43
J 0
(-615 3010);
DISPLAY 0.680851 (-615 3010);
PAINT MONO (-615 3010);
FORCEPROP 0 LASTPIN (-625 3050) $PN 46
J 0
(-615 3060);
DISPLAY 0.680851 (-615 3060);
PAINT MONO (-615 3060);
FORCEPROP 0 LASTPIN (-625 3100) $PN 48
J 0
(-615 3110);
DISPLAY 0.680851 (-615 3110);
PAINT MONO (-615 3110);
FORCEPROP 0 LASTPIN (-625 3150) $PN 50
J 0
(-615 3160);
DISPLAY 0.680851 (-615 3160);
PAINT MONO (-615 3160);
FORCEPROP 0 LASTPIN (-625 3200) $PN 52
J 0
(-615 3210);
DISPLAY 0.680851 (-615 3210);
PAINT MONO (-615 3210);
FORCEPROP 0 LASTPIN (-625 3250) $PN 54
J 0
(-615 3260);
DISPLAY 0.680851 (-615 3260);
PAINT MONO (-615 3260);
FORCEPROP 0 LASTPIN (-625 3300) $PN 57
J 0
(-615 3310);
DISPLAY 0.680851 (-615 3310);
PAINT MONO (-615 3310);
FORCEPROP 0 LASTPIN (-625 3350) $PN 59
J 0
(-615 3360);
DISPLAY 0.680851 (-615 3360);
PAINT MONO (-615 3360);
FORCEPROP 0 LASTPIN (-625 3400) $PN 61
J 0
(-615 3410);
DISPLAY 0.680851 (-615 3410);
PAINT MONO (-615 3410);
FORCEPROP 0 LASTPIN (-625 3450) $PN 63
J 0
(-615 3460);
DISPLAY 0.680851 (-615 3460);
PAINT MONO (-615 3460);
FORCEPROP 0 LASTPIN (-625 3500) $PN 65
J 0
(-615 3510);
DISPLAY 0.680851 (-615 3510);
PAINT MONO (-615 3510);
FORCEPROP 0 LASTPIN (-625 3550) $PN 67
J 0
(-615 3560);
DISPLAY 0.680851 (-615 3560);
PAINT MONO (-615 3560);
FORCEPROP 0 LASTPIN (-625 3600) $PN 69
J 0
(-615 3610);
DISPLAY 0.680851 (-615 3610);
PAINT MONO (-615 3610);
FORCEPROP 0 LASTPIN (-625 3650) $PN 71
J 0
(-615 3660);
DISPLAY 0.680851 (-615 3660);
PAINT MONO (-615 3660);
FORCEPROP 0 LASTPIN (-625 3700) $PN 73
J 0
(-615 3710);
DISPLAY 0.680851 (-615 3710);
PAINT MONO (-615 3710);
FORCEPROP 0 LASTPIN (-625 3750) $PN 75
J 0
(-615 3760);
DISPLAY 0.680851 (-615 3760);
PAINT MONO (-615 3760);
FORCEPROP 0 LASTPIN (-625 3800) $PN 77
J 0
(-615 3810);
DISPLAY 0.680851 (-615 3810);
PAINT MONO (-615 3810);
FORCEPROP 0 LASTPIN (-625 3850) $PN 79
J 0
(-615 3860);
DISPLAY 0.680851 (-615 3860);
PAINT MONO (-615 3860);
FORCEPROP 0 LASTPIN (-625 3900) $PN 81
J 0
(-615 3910);
DISPLAY 0.680851 (-615 3910);
PAINT MONO (-615 3910);
FORCEPROP 0 LASTPIN (-625 3950) $PN 83
J 0
(-615 3960);
DISPLAY 0.680851 (-615 3960);
PAINT MONO (-615 3960);
FORCEPROP 0 LASTPIN (-625 4000) $PN 85
J 0
(-615 4010);
DISPLAY 0.680851 (-615 4010);
PAINT MONO (-615 4010);
FORCEPROP 0 LASTPIN (-625 4050) $PN 88
J 0
(-615 4060);
DISPLAY 0.680851 (-615 4060);
PAINT MONO (-615 4060);
FORCEPROP 0 LASTPIN (-625 4100) $PN 90
J 0
(-615 4110);
DISPLAY 0.680851 (-615 4110);
PAINT MONO (-615 4110);
FORCEPROP 0 LASTPIN (-625 4150) $PN 92
J 0
(-615 4160);
DISPLAY 0.680851 (-615 4160);
PAINT MONO (-615 4160);
FORCEPROP 0 LASTPIN (-625 4200) $PN 95
J 0
(-615 4210);
DISPLAY 0.680851 (-615 4210);
PAINT MONO (-615 4210);
FORCEPROP 0 LASTPIN (-625 4250) $PN 97
J 0
(-615 4260);
DISPLAY 0.680851 (-615 4260);
PAINT MONO (-615 4260);
FORCEPROP 0 LASTPIN (-625 4300) $PN 99
J 0
(-615 4310);
DISPLAY 0.680851 (-615 4310);
PAINT MONO (-615 4310);
FORCEPROP 0 LASTPIN (-625 4350) $PN 101
J 0
(-615 4360);
DISPLAY 0.680851 (-615 4360);
PAINT MONO (-615 4360);
FORCEPROP 0 LASTPIN (-625 4400) $PN 103
J 0
(-615 4410);
DISPLAY 0.680851 (-615 4410);
PAINT MONO (-615 4410);
FORCEPROP 0 LASTPIN (-625 4450) $PN 106
J 0
(-615 4460);
DISPLAY 0.680851 (-615 4460);
PAINT MONO (-615 4460);
FORCEPROP 0 LASTPIN (-625 4500) $PN 108
J 0
(-615 4510);
DISPLAY 0.680851 (-615 4510);
PAINT MONO (-615 4510);
FORCEPROP 0 LASTPIN (-625 4550) $PN 110
J 0
(-615 4560);
DISPLAY 0.680851 (-615 4560);
PAINT MONO (-615 4560);
FORCEPROP 0 LASTPIN (-625 4600) $PN 112
J 0
(-615 4610);
DISPLAY 0.680851 (-615 4610);
PAINT MONO (-615 4610);
FORCEPROP 0 LASTPIN (-625 4650) $PN 114
J 0
(-615 4660);
DISPLAY 0.680851 (-615 4660);
PAINT MONO (-615 4660);
FORCEPROP 0 LASTPIN (-625 4700) $PN 117
J 0
(-615 4710);
DISPLAY 0.680851 (-615 4710);
PAINT MONO (-615 4710);
FORCEPROP 0 LASTPIN (-625 4750) $PN 119
J 0
(-615 4760);
DISPLAY 0.680851 (-615 4760);
PAINT MONO (-615 4760);
FORCEPROP 0 LASTPIN (-625 4800) $PN 121
J 0
(-615 4810);
DISPLAY 0.680851 (-615 4810);
PAINT MONO (-615 4810);
FORCEPROP 0 LASTPIN (-625 4850) $PN 123
J 0
(-615 4860);
DISPLAY 0.680851 (-615 4860);
PAINT MONO (-615 4860);
FORCEPROP 0 LASTPIN (-625 4900) $PN 125
J 0
(-615 4910);
DISPLAY 0.680851 (-615 4910);
PAINT MONO (-615 4910);
FORCEPROP 0 LASTPIN (-625 4950) $PN 128
J 0
(-615 4960);
DISPLAY 0.680851 (-615 4960);
PAINT MONO (-615 4960);
FORCEPROP 0 LASTPIN (-625 5000) $PN 130
J 0
(-615 5010);
DISPLAY 0.680851 (-615 5010);
PAINT MONO (-615 5010);
FORCEPROP 0 LASTPIN (-625 5050) $PN 132
J 0
(-615 5060);
DISPLAY 0.680851 (-615 5060);
PAINT MONO (-615 5060);
FORCEPROP 0 LASTPIN (-625 5100) $PN 134
J 0
(-615 5110);
DISPLAY 0.680851 (-615 5110);
PAINT MONO (-615 5110);
FORCEPROP 0 LASTPIN (-625 5150) $PN 136
J 0
(-615 5160);
DISPLAY 0.680851 (-615 5160);
PAINT MONO (-615 5160);
FORCEPROP 0 LASTPIN (-625 5200) $PN 139
J 0
(-615 5210);
DISPLAY 0.680851 (-615 5210);
PAINT MONO (-615 5210);
FORCEPROP 0 LASTPIN (-625 5250) $PN 141
J 0
(-615 5260);
DISPLAY 0.680851 (-615 5260);
PAINT MONO (-615 5260);
FORCEPROP 0 LASTPIN (-625 5300) $PN 143
J 0
(-615 5310);
DISPLAY 0.680851 (-615 5310);
PAINT MONO (-615 5310);
FORCEPROP 0 LASTPIN (-1825 2050) $PN 151
J 2
(-1835 2060);
DISPLAY 0.680851 (-1835 2060);
PAINT MONO (-1835 2060);
FORCEPROP 0 LASTPIN (-1825 2100) $PN 153
J 2
(-1835 2110);
DISPLAY 0.680851 (-1835 2110);
PAINT MONO (-1835 2110);
FORCEPROP 0 LASTPIN (-1825 2150) $PN 155
J 2
(-1835 2160);
DISPLAY 0.680851 (-1835 2160);
PAINT MONO (-1835 2160);
FORCEPROP 0 LASTPIN (-1825 2200) $PN 158
J 2
(-1835 2210);
DISPLAY 0.680851 (-1835 2210);
PAINT MONO (-1835 2210);
FORCEPROP 0 LASTPIN (-1825 2250) $PN 160
J 2
(-1835 2260);
DISPLAY 0.680851 (-1835 2260);
PAINT MONO (-1835 2260);
FORCEPROP 0 LASTPIN (-1825 2300) $PN 162
J 2
(-1835 2310);
DISPLAY 0.680851 (-1835 2310);
PAINT MONO (-1835 2310);
FORCEPROP 0 LASTPIN (-1825 2350) $PN 164
J 2
(-1835 2360);
DISPLAY 0.680851 (-1835 2360);
PAINT MONO (-1835 2360);
FORCEPROP 0 LASTPIN (-1825 2400) $PN 166
J 2
(-1835 2410);
DISPLAY 0.680851 (-1835 2410);
PAINT MONO (-1835 2410);
FORCEPROP 0 LASTPIN (-1825 2450) $PN 169
J 2
(-1835 2460);
DISPLAY 0.680851 (-1835 2460);
PAINT MONO (-1835 2460);
FORCEPROP 0 LASTPIN (-1825 2500) $PN 171
J 2
(-1835 2510);
DISPLAY 0.680851 (-1835 2510);
PAINT MONO (-1835 2510);
FORCEPROP 0 LASTPIN (-1825 2550) $PN 173
J 2
(-1835 2560);
DISPLAY 0.680851 (-1835 2560);
PAINT MONO (-1835 2560);
FORCEPROP 0 LASTPIN (-1825 2600) $PN 175
J 2
(-1835 2610);
DISPLAY 0.680851 (-1835 2610);
PAINT MONO (-1835 2610);
FORCEPROP 0 LASTPIN (-1825 2650) $PN 177
J 2
(-1835 2660);
DISPLAY 0.680851 (-1835 2660);
PAINT MONO (-1835 2660);
FORCEPROP 0 LASTPIN (-1825 2700) $PN 180
J 2
(-1835 2710);
DISPLAY 0.680851 (-1835 2710);
PAINT MONO (-1835 2710);
FORCEPROP 0 LASTPIN (-1825 2750) $PN 182
J 2
(-1835 2760);
DISPLAY 0.680851 (-1835 2760);
PAINT MONO (-1835 2760);
FORCEPROP 0 LASTPIN (-1825 2800) $PN 184
J 2
(-1835 2810);
DISPLAY 0.680851 (-1835 2810);
PAINT MONO (-1835 2810);
FORCEPROP 0 LASTPIN (-1825 2850) $PN 186
J 2
(-1835 2860);
DISPLAY 0.680851 (-1835 2860);
PAINT MONO (-1835 2860);
FORCEPROP 0 LASTPIN (-1825 2900) $PN 188
J 2
(-1835 2910);
DISPLAY 0.680851 (-1835 2910);
PAINT MONO (-1835 2910);
FORCEPROP 0 LASTPIN (-1825 2950) $PN 191
J 2
(-1835 2960);
DISPLAY 0.680851 (-1835 2960);
PAINT MONO (-1835 2960);
FORCEPROP 0 LASTPIN (-1825 3000) $PN 193
J 2
(-1835 3010);
DISPLAY 0.680851 (-1835 3010);
PAINT MONO (-1835 3010);
FORCEPROP 0 LASTPIN (-1825 3050) $PN 195
J 2
(-1835 3060);
DISPLAY 0.680851 (-1835 3060);
PAINT MONO (-1835 3060);
FORCEPROP 0 LASTPIN (-1825 3100) $PN 197
J 2
(-1835 3110);
DISPLAY 0.680851 (-1835 3110);
PAINT MONO (-1835 3110);
FORCEPROP 0 LASTPIN (-1825 3150) $PN 199
J 2
(-1835 3160);
DISPLAY 0.680851 (-1835 3160);
PAINT MONO (-1835 3160);
FORCEPROP 0 LASTPIN (-1825 3200) $PN 202
J 2
(-1835 3210);
DISPLAY 0.680851 (-1835 3210);
PAINT MONO (-1835 3210);
FORCEPROP 0 LASTPIN (-1825 3250) $PN 204
J 2
(-1835 3260);
DISPLAY 0.680851 (-1835 3260);
PAINT MONO (-1835 3260);
FORCEPROP 0 LASTPIN (-1825 3300) $PN 206
J 2
(-1835 3310);
DISPLAY 0.680851 (-1835 3310);
PAINT MONO (-1835 3310);
FORCEPROP 0 LASTPIN (-1825 3350) $PN 208
J 2
(-1835 3360);
DISPLAY 0.680851 (-1835 3360);
PAINT MONO (-1835 3360);
FORCEPROP 0 LASTPIN (-1825 3400) $PN 210
J 2
(-1835 3410);
DISPLAY 0.680851 (-1835 3410);
PAINT MONO (-1835 3410);
FORCEPROP 0 LASTPIN (-1825 3450) $PN 212
J 2
(-1835 3460);
DISPLAY 0.680851 (-1835 3460);
PAINT MONO (-1835 3460);
FORCEPROP 0 LASTPIN (-1825 3500) $PN 214
J 2
(-1835 3510);
DISPLAY 0.680851 (-1835 3510);
PAINT MONO (-1835 3510);
FORCEPROP 0 LASTPIN (-1825 3550) $PN 216
J 2
(-1835 3560);
DISPLAY 0.680851 (-1835 3560);
PAINT MONO (-1835 3560);
FORCEPROP 0 LASTPIN (-1825 3600) $PN 219
J 2
(-1835 3610);
DISPLAY 0.680851 (-1835 3610);
PAINT MONO (-1835 3610);
FORCEPROP 0 LASTPIN (-1825 3650) $PN 222
J 2
(-1835 3660);
DISPLAY 0.680851 (-1835 3660);
PAINT MONO (-1835 3660);
FORCEPROP 0 LASTPIN (-1825 3700) $PN 224
J 2
(-1835 3710);
DISPLAY 0.680851 (-1835 3710);
PAINT MONO (-1835 3710);
FORCEPROP 0 LASTPIN (-1825 3750) $PN 226
J 2
(-1835 3760);
DISPLAY 0.680851 (-1835 3760);
PAINT MONO (-1835 3760);
FORCEPROP 0 LASTPIN (-1825 3800) $PN 228
J 2
(-1835 3810);
DISPLAY 0.680851 (-1835 3810);
PAINT MONO (-1835 3810);
FORCEPROP 0 LASTPIN (-1825 3850) $PN 230
J 2
(-1835 3860);
DISPLAY 0.680851 (-1835 3860);
PAINT MONO (-1835 3860);
FORCEPROP 0 LASTPIN (-1825 3900) $PN 233
J 2
(-1835 3910);
DISPLAY 0.680851 (-1835 3910);
PAINT MONO (-1835 3910);
FORCEPROP 0 LASTPIN (-1825 3950) $PN 235
J 2
(-1835 3960);
DISPLAY 0.680851 (-1835 3960);
PAINT MONO (-1835 3960);
FORCEPROP 0 LASTPIN (-1825 4000) $PN 237
J 2
(-1835 4010);
DISPLAY 0.680851 (-1835 4010);
PAINT MONO (-1835 4010);
FORCEPROP 0 LASTPIN (-1825 4050) $PN 240
J 2
(-1835 4060);
DISPLAY 0.680851 (-1835 4060);
PAINT MONO (-1835 4060);
FORCEPROP 0 LASTPIN (-1825 4100) $PN 242
J 2
(-1835 4110);
DISPLAY 0.680851 (-1835 4110);
PAINT MONO (-1835 4110);
FORCEPROP 0 LASTPIN (-1825 4150) $PN 244
J 2
(-1835 4160);
DISPLAY 0.680851 (-1835 4160);
PAINT MONO (-1835 4160);
FORCEPROP 0 LASTPIN (-1825 4200) $PN 246
J 2
(-1835 4210);
DISPLAY 0.680851 (-1835 4210);
PAINT MONO (-1835 4210);
FORCEPROP 0 LASTPIN (-1825 4250) $PN 248
J 2
(-1835 4260);
DISPLAY 0.680851 (-1835 4260);
PAINT MONO (-1835 4260);
FORCEPROP 0 LASTPIN (-1825 4300) $PN 251
J 2
(-1835 4310);
DISPLAY 0.680851 (-1835 4310);
PAINT MONO (-1835 4310);
FORCEPROP 0 LASTPIN (-1825 4350) $PN 253
J 2
(-1835 4360);
DISPLAY 0.680851 (-1835 4360);
PAINT MONO (-1835 4360);
FORCEPROP 0 LASTPIN (-1825 4400) $PN 255
J 2
(-1835 4410);
DISPLAY 0.680851 (-1835 4410);
PAINT MONO (-1835 4410);
FORCEPROP 0 LASTPIN (-1825 4450) $PN 257
J 2
(-1835 4460);
DISPLAY 0.680851 (-1835 4460);
PAINT MONO (-1835 4460);
FORCEPROP 0 LASTPIN (-1825 4500) $PN 259
J 2
(-1835 4510);
DISPLAY 0.680851 (-1835 4510);
PAINT MONO (-1835 4510);
FORCEPROP 0 LASTPIN (-1825 4550) $PN 262
J 2
(-1835 4560);
DISPLAY 0.680851 (-1835 4560);
PAINT MONO (-1835 4560);
FORCEPROP 0 LASTPIN (-1825 4600) $PN 264
J 2
(-1835 4610);
DISPLAY 0.680851 (-1835 4610);
PAINT MONO (-1835 4610);
FORCEPROP 0 LASTPIN (-1825 4650) $PN 266
J 2
(-1835 4660);
DISPLAY 0.680851 (-1835 4660);
PAINT MONO (-1835 4660);
FORCEPROP 0 LASTPIN (-1825 4700) $PN 268
J 2
(-1835 4710);
DISPLAY 0.680851 (-1835 4710);
PAINT MONO (-1835 4710);
FORCEPROP 0 LASTPIN (-1825 4750) $PN 270
J 2
(-1835 4760);
DISPLAY 0.680851 (-1835 4760);
PAINT MONO (-1835 4760);
FORCEPROP 0 LASTPIN (-1825 4800) $PN 273
J 2
(-1835 4810);
DISPLAY 0.680851 (-1835 4810);
PAINT MONO (-1835 4810);
FORCEPROP 0 LASTPIN (-1825 4850) $PN 275
J 2
(-1835 4860);
DISPLAY 0.680851 (-1835 4860);
PAINT MONO (-1835 4860);
FORCEPROP 0 LASTPIN (-1825 4900) $PN 277
J 2
(-1835 4910);
DISPLAY 0.680851 (-1835 4910);
PAINT MONO (-1835 4910);
FORCEPROP 0 LASTPIN (-1825 4950) $PN 279
J 2
(-1835 4960);
DISPLAY 0.680851 (-1835 4960);
PAINT MONO (-1835 4960);
FORCEPROP 0 LASTPIN (-1825 5000) $PN 281
J 2
(-1835 5010);
DISPLAY 0.680851 (-1835 5010);
PAINT MONO (-1835 5010);
FORCEPROP 0 LASTPIN (-1825 5050) $PN 284
J 2
(-1835 5060);
DISPLAY 0.680851 (-1835 5060);
PAINT MONO (-1835 5060);
FORCEPROP 0 LASTPIN (-1825 5100) $PN 286
J 2
(-1835 5110);
DISPLAY 0.680851 (-1835 5110);
PAINT MONO (-1835 5110);
FORCEPROP 0 LASTPIN (-1825 5150) $PN 288
J 2
(-1835 5160);
DISPLAY 0.680851 (-1835 5160);
PAINT MONO (-1835 5160);
FORCEPROP 2 LAST PART_TYPE SMLF
J 0
(-1675 5725);
DISPLAY 1.021277 (-1675 5725);
FORCEPROP 1 LAST MATERIAL IO
J 0
(-1675 5475);
DISPLAY 0.468085 (-1675 5475);
PAINT SKYBLUE (-1675 5475);
FORCEPROP 2 LAST VALUE SCONN288_DDR506112002KQ
J 0
(-1675 5675);
DISPLAY 0.489362 (-1675 5675);
PAINT SKYBLUE (-1675 5675);
FORCEPROP 1 LAST CDS_LMAN_SYM_OUTLINE -450,1800,450,-1750
J 0
(-1225 3650);
DISPLAY 0.468085 (-1225 3650);
PAINT GREEN (-1225 3650);
DISPLAY INVISIBLE (-1225 3650);
FORCEPROP 1 LAST NEEDS_NO_SIZE TRUE
J 0
(-1225 3650);
DISPLAY 0.723404 (-1225 3650);
PAINT GREEN (-1225 3650);
DISPLAY INVISIBLE (-1225 3650);
FORCEPROP 2 LAST CDS_LIB pure_quanta
J 0
(-1225 3650);
DISPLAY INVISIBLE (-1225 3650);
FORCEPROP 1 LAST PATH I174
J 0
(-1225 3650);
DISPLAY 0.723404 (-1225 3650);
PAINT GREEN (-1225 3650);
DISPLAY INVISIBLE (-1225 3650);
FORCEPROP 1 LAST PART_NUMBER DFHST8FS479
J 0
(-1675 5550);
DISPLAY 0.468085 (-1675 5550);
PAINT SKYBLUE (-1675 5550);
DISPLAY INVISIBLE (-1675 5550);
FORCEADD OFFPAGE..1
(-8250 4450);
FORCEPROP 2 LAST $XR0 44 
J 0
(-8501 4450);
DISPLAY 0.638298 (-8501 4450);
PAINT MONO (-8501 4450);
FORCEPROP 2 LAST CDS_LIB mstr_standard
J 0
(-8250 4450);
DISPLAY 0.723404 (-8250 4450);
PAINT MONO (-8250 4450);
DISPLAY INVISIBLE (-8250 4450);
FORCEPROP 1 LAST OFFPAGE TRUE
J 0
(-7925 4325);
DISPLAY 0.872340 (-7925 4325);
PAINT GREEN (-7925 4325);
DISPLAY INVISIBLE (-7925 4325);
FORCEPROP 1 LAST COMMENT_BODY TRUE
J 0
(-8125 4350);
DISPLAY 0.872340 (-8125 4350);
PAINT GREEN (-8125 4350);
DISPLAY INVISIBLE (-8125 4350);
FORCEPROP 2 LAST PATH I18
J 0
(-8450 4500);
DISPLAY 1.021277 (-8450 4500);
DISPLAY INVISIBLE (-8450 4500);
FORCEADD Q_CAP..1
R 2
(-8575 3225);
FORCEPROP 1 LAST LOCATION C164
J 2
(-8625 3325);
DISPLAY 0.489362 (-8625 3325);
PAINT SKYBLUE (-8625 3325);
FORCEPROP 0 LAST $SEC 1
J 0
(-8625 3375);
DISPLAY 0.680851 (-8625 3375);
PAINT MONO (-8625 3375);
DISPLAY INVISIBLE (-8625 3375);
FORCEPROP 0 LAST CDS_SEC 1
J 0
(-8625 3375);
DISPLAY 1.021277 (-8625 3375);
DISPLAY INVISIBLE (-8625 3375);
FORCEPROP 1 LASTPIN (-8575 3325) $PN 1
J 2
(-8585 3305);
DISPLAY 0.489362 (-8585 3305);
PAINT MONO (-8585 3305);
FORCEPROP 1 LASTPIN (-8575 3125) $PN 2
J 2
(-8585 3105);
DISPLAY 0.489362 (-8585 3105);
PAINT MONO (-8585 3105);
FORCEPROP 1 LAST PACK_TYPE 0402
J 2
(-8625 3025);
DISPLAY 0.489362 (-8625 3025);
PAINT SKYBLUE (-8625 3025);
FORCEPROP 1 LAST VALUE 0.1UF
J 2
(-8625 3275);
DISPLAY 0.489362 (-8625 3275);
PAINT SKYBLUE (-8625 3275);
FORCEPROP 1 LAST VOLTAGE 25V
J 2
(-8625 3225);
DISPLAY 0.489362 (-8625 3225);
PAINT SKYBLUE (-8625 3225);
FORCEPROP 1 LAST TOLERANCE 10%
J 2
(-8625 3175);
DISPLAY 0.489362 (-8625 3175);
PAINT SKYBLUE (-8625 3175);
FORCEPROP 1 LAST MATERIAL X7R
J 2
(-8625 3125);
DISPLAY 0.489362 (-8625 3125);
PAINT SKYBLUE (-8625 3125);
FORCEPROP 2 LAST CDS_LIB pure_quanta
J 0
(-8575 3225);
DISPLAY INVISIBLE (-8575 3225);
FORCEPROP 0 LAST BOM_COST MEM
J 2
(-8630 3370);
DISPLAY 0.595745 (-8630 3370);
PAINT MONO (-8630 3370);
DISPLAY INVISIBLE (-8630 3370);
FORCEPROP 2 LAST ROOM 
J 2
(-8630 3370);
DISPLAY 0.595745 (-8630 3370);
PAINT RED (-8630 3370);
DISPLAY INVISIBLE (-8630 3370);
FORCEPROP 1 LAST PATH I185
J 2
(-8625 3375);
DISPLAY 0.978723 (-8625 3375);
PAINT WHITE (-8625 3375);
DISPLAY INVISIBLE (-8625 3375);
FORCEPROP 1 LAST PART_NUMBER CH4104K1B00
J 2
(-8625 3075);
DISPLAY 0.489362 (-8625 3075);
PAINT SKYBLUE (-8625 3075);
DISPLAY INVISIBLE (-8625 3075);
FORCEADD GND..1
(-8575 3000);
FORCEPROP 3 LASTPIN (-8575 3050) SIG_NAME GND\g
J 0
(-8565 3060);
DISPLAY 0.659574 (-8565 3060);
PAINT MONO (-8565 3060);
DISPLAY INVISIBLE (-8565 3060);
FORCEPROP 2 LAST BOM_COST MEM
J 0
(-8550 3125);
DISPLAY 0.659574 (-8550 3125);
DISPLAY INVISIBLE (-8550 3125);
FORCEPROP 1 LAST SIZE 1B
J 0
(-8500 2950);
DISPLAY 0.723404 (-8500 2950);
PAINT GREEN (-8500 2950);
DISPLAY INVISIBLE (-8500 2950);
FORCEPROP 2 LAST CDS_LIB mstr_symbols
J 0
(-8575 3000);
DISPLAY 0.808511 (-8575 3000);
DISPLAY INVISIBLE (-8575 3000);
FORCEPROP 1 LAST VOLTAGE 0
J 0
(-8595 3095);
DISPLAY 0.829787 (-8595 3095);
PAINT SKYBLUE (-8595 3095);
DISPLAY INVISIBLE (-8595 3095);
FORCEPROP 2 LAST ROOM MEM_EFGH_DECOUPLING_CAPS
J 0
(-8550 3075);
DISPLAY 0.659574 (-8550 3075);
PAINT RED (-8550 3075);
DISPLAY INVISIBLE (-8550 3075);
FORCEPROP 1 LAST BODY_TYPE PLUMBING
J 0
(-8620 2957);
DISPLAY 0.276596 (-8620 2957);
PAINT GREEN (-8620 2957);
DISPLAY INVISIBLE (-8620 2957);
FORCEPROP 1 LAST HDL_POWER GND
J 0
(-8575 3150);
DISPLAY 0.723404 (-8575 3150);
PAINT GREEN (-8575 3150);
DISPLAY INVISIBLE (-8575 3150);
FORCEPROP 1 LAST PATH I186
J 0
(-8500 3000);
DISPLAY 0.872340 (-8500 3000);
PAINT AQUA (-8500 3000);
DISPLAY INVISIBLE (-8500 3000);
FORCEADD OFFPAGE..6
(-9025 2150);
FORCEPROP 2 LAST $XR4 109 
J 0
(-9305 2222);
DISPLAY 0.638298 (-9305 2222);
PAINT MONO (-9305 2222);
FORCEPROP 2 LAST $XR3 108 
J 0
(-9305 2078);
DISPLAY 0.638298 (-9305 2078);
PAINT MONO (-9305 2078);
FORCEPROP 2 LAST $XR2 107 
J 0
(-9305 2186);
DISPLAY 0.638298 (-9305 2186);
PAINT MONO (-9305 2186);
FORCEPROP 2 LAST $XR1 106 
J 0
(-9305 2114);
DISPLAY 0.638298 (-9305 2114);
PAINT MONO (-9305 2114);
FORCEPROP 2 LAST $XR0 104 
J 0
(-9305 2150);
DISPLAY 0.638298 (-9305 2150);
PAINT MONO (-9305 2150);
FORCEPROP 2 LAST CDS_LIB mstr_standard
J 0
(-9025 2150);
DISPLAY INVISIBLE (-9025 2150);
FORCEPROP 1 LAST OFFPAGE TRUE
J 0
(-8700 2025);
DISPLAY 0.872340 (-8700 2025);
PAINT GREEN (-8700 2025);
DISPLAY INVISIBLE (-8700 2025);
FORCEPROP 1 LAST COMMENT_BODY TRUE
J 0
(-8925 2075);
DISPLAY 0.872340 (-8925 2075);
PAINT GREEN (-8925 2075);
DISPLAY INVISIBLE (-8925 2075);
FORCEPROP 2 LAST PATH I187
J 0
(-8975 2225);
DISPLAY 1.021277 (-8975 2225);
DISPLAY INVISIBLE (-8975 2225);
FORCEADD Q_RES..1
R 2
(-8475 2150);
FORCEPROP 1 LAST LOCATION R310
J 2
(-8425 2200);
DISPLAY 0.489362 (-8425 2200);
PAINT SKYBLUE (-8425 2200);
FORCEPROP 0 LAST $SEC 1
J 0
(-8425 2250);
DISPLAY 0.680851 (-8425 2250);
PAINT MONO (-8425 2250);
DISPLAY INVISIBLE (-8425 2250);
FORCEPROP 0 LAST CDS_SEC 1
J 0
(-8425 2250);
DISPLAY 1.021277 (-8425 2250);
DISPLAY INVISIBLE (-8425 2250);
FORCEPROP 1 LASTPIN (-8375 2150) $PN 1
J 2
(-8387 2162);
DISPLAY 0.489362 (-8387 2162);
PAINT MONO (-8387 2162);
FORCEPROP 1 LASTPIN (-8575 2150) $PN 2
J 2
(-8537 2162);
DISPLAY 0.489362 (-8537 2162);
PAINT MONO (-8537 2162);
FORCEPROP 1 LAST VALUE 1K
J 0
(-8475 2100);
DISPLAY 0.489362 (-8475 2100);
PAINT SKYBLUE (-8475 2100);
FORCEPROP 1 LAST TOLERANCE 1%
J 2
(-8350 2125);
DISPLAY 0.489362 (-8350 2125);
PAINT SKYBLUE (-8350 2125);
DISPLAY INVISIBLE (-8350 2125);
FORCEPROP 2 LAST BOM_COST MEM
J 0
(-8500 2300);
DISPLAY 0.744681 (-8500 2300);
PAINT WHITE (-8500 2300);
DISPLAY INVISIBLE (-8500 2300);
FORCEPROP 2 LAST CDS_LIB pure_quanta
J 0
(-8475 2150);
DISPLAY INVISIBLE (-8475 2150);
FORCEPROP 1 LAST WATTAGE 1/16W
J 0
(-8400 2075);
DISPLAY 0.489362 (-8400 2075);
PAINT SKYBLUE (-8400 2075);
DISPLAY INVISIBLE (-8400 2075);
FORCEPROP 1 LAST MATERIAL CHIP
J 0
(-8650 2125);
DISPLAY 0.489362 (-8650 2125);
PAINT SKYBLUE (-8650 2125);
DISPLAY INVISIBLE (-8650 2125);
FORCEPROP 1 LAST PACK_TYPE 0402LF
J 0
(-8650 2075);
DISPLAY 0.489362 (-8650 2075);
PAINT SKYBLUE (-8650 2075);
DISPLAY INVISIBLE (-8650 2075);
FORCEPROP 2 LAST ROOM 
J 0
(-8500 2250);
DISPLAY 0.744681 (-8500 2250);
PAINT RED (-8500 2250);
DISPLAY INVISIBLE (-8500 2250);
FORCEPROP 1 LAST PATH I189
J 2
(-8425 2300);
DISPLAY 0.978723 (-8425 2300);
PAINT WHITE (-8425 2300);
DISPLAY INVISIBLE (-8425 2300);
FORCEPROP 1 LAST PART_NUMBER CS21002FB06
J 0
(-8575 2200);
DISPLAY 0.489362 (-8575 2200);
PAINT SKYBLUE (-8575 2200);
DISPLAY INVISIBLE (-8575 2200);
FORCEADD OFFPAGE..1
(-8250 4600);
FORCEPROP 2 LAST $XR0 44 
J 0
(-8501 4600);
DISPLAY 0.638298 (-8501 4600);
PAINT MONO (-8501 4600);
FORCEPROP 2 LAST CDS_LIB mstr_standard
J 0
(-8250 4600);
DISPLAY 0.723404 (-8250 4600);
PAINT MONO (-8250 4600);
DISPLAY INVISIBLE (-8250 4600);
FORCEPROP 1 LAST OFFPAGE TRUE
J 0
(-7925 4475);
DISPLAY 0.872340 (-7925 4475);
PAINT GREEN (-7925 4475);
DISPLAY INVISIBLE (-7925 4475);
FORCEPROP 1 LAST COMMENT_BODY TRUE
J 0
(-8125 4500);
DISPLAY 0.872340 (-8125 4500);
PAINT GREEN (-8125 4500);
DISPLAY INVISIBLE (-8125 4500);
FORCEPROP 2 LAST PATH I19
J 0
(-8450 4650);
DISPLAY 1.021277 (-8450 4650);
DISPLAY INVISIBLE (-8450 4650);
FORCEADD Q_RES..2
(-8350 2300);
FORCEPROP 1 LAST LOCATION R111
J 0
(-8305 2425);
DISPLAY 0.489362 (-8305 2425);
PAINT SKYBLUE (-8305 2425);
FORCEPROP 0 LAST $SEC 1
J 0
(-8300 2475);
DISPLAY 0.680851 (-8300 2475);
PAINT MONO (-8300 2475);
DISPLAY INVISIBLE (-8300 2475);
FORCEPROP 0 LAST CDS_SEC 1
J 0
(-8300 2475);
DISPLAY 1.021277 (-8300 2475);
DISPLAY INVISIBLE (-8300 2475);
FORCEPROP 1 LASTPIN (-8350 2400) $PN 1
J 0
(-8345 2362);
DISPLAY 0.489362 (-8345 2362);
PAINT MONO (-8345 2362);
FORCEPROP 1 LASTPIN (-8350 2200) $PN 2
J 0
(-8345 2210);
DISPLAY 0.489362 (-8345 2210);
PAINT MONO (-8345 2210);
FORCEPROP 1 LAST TOLERANCE 1%
J 0
(-8300 2350);
DISPLAY 0.489362 (-8300 2350);
PAINT SKYBLUE (-8300 2350);
FORCEPROP 1 LAST WATTAGE 1/16W
J 0
(-8300 2325);
DISPLAY 0.489362 (-8300 2325);
PAINT SKYBLUE (-8300 2325);
FORCEPROP 1 LAST MATERIAL EMPTY
J 0
(-8300 2300);
DISPLAY 0.489362 (-8300 2300);
PAINT RED (-8300 2300);
FORCEPROP 1 LAST PACK_TYPE 0402LF
J 0
(-8300 2250);
DISPLAY 0.489362 (-8300 2250);
PAINT SKYBLUE (-8300 2250);
FORCEPROP 1 LAST VALUE 1K
J 0
(-8305 2375);
DISPLAY 0.489362 (-8305 2375);
PAINT SKYBLUE (-8305 2375);
FORCEPROP 2 LAST BOM_COST MEM
J 0
(-8300 2475);
DISPLAY 0.808511 (-8300 2475);
DISPLAY INVISIBLE (-8300 2475);
FORCEPROP 2 LAST CDS_LIB pure_quanta
J 0
(-8350 2300);
DISPLAY INVISIBLE (-8350 2300);
FORCEPROP 2 LAST ROOM 
J 0
(-8300 2525);
DISPLAY 0.808511 (-8300 2525);
PAINT RED (-8300 2525);
DISPLAY INVISIBLE (-8300 2525);
FORCEPROP 1 LAST PATH I190
J 0
(-8300 2475);
DISPLAY 0.978723 (-8300 2475);
PAINT WHITE (-8300 2475);
DISPLAY INVISIBLE (-8300 2475);
FORCEPROP 1 LAST PART_NUMBER CS21002FB06
J 0
(-8300 2275);
DISPLAY 0.489362 (-8300 2275);
PAINT SKYBLUE (-8300 2275);
DISPLAY INVISIBLE (-8300 2275);
FORCEADD VCC_CORE..1
(-8350 2475);
FORCEPROP 3 LASTPIN (-8350 2425) SIG_NAME P3V3\g
J 0
(-8340 2435);
DISPLAY 0.659574 (-8340 2435);
PAINT MONO (-8340 2435);
DISPLAY INVISIBLE (-8340 2435);
FORCEPROP 1 LAST HDL_POWER P3V3
J 1
(-8350 2525);
DISPLAY 0.489362 (-8350 2525);
PAINT GREEN (-8350 2525);
FORCEPROP 2 LAST CDS_LIB mstr_symbols
J 0
(-8350 2475);
DISPLAY INVISIBLE (-8350 2475);
FORCEPROP 0 LAST VOLTAGE 3.3
J 0
(-8625 2625);
DISPLAY 1.021277 (-8625 2625);
PAINT SKYBLUE (-8625 2625);
DISPLAY INVISIBLE (-8625 2625);
FORCEPROP 2 LAST ROOM PVCCINFAON_CPU0_CTRL
J 0
(-8350 2575);
DISPLAY 0.808511 (-8350 2575);
PAINT RED (-8350 2575);
DISPLAY INVISIBLE (-8350 2575);
FORCEPROP 1 LAST PATH I192
J 0
(-8300 2500);
DISPLAY 0.872340 (-8300 2500);
PAINT AQUA (-8300 2500);
DISPLAY INVISIBLE (-8300 2500);
FORCEADD TAP..1
(-3225 3675);
FORCEPROP 3 LASTPIN (-3275 3675) SIG_NAME M_H_CPU1_SA_DQS_DN<2>
J 0
(-3265 3685);
DISPLAY 0.659574 (-3265 3685);
PAINT MONO (-3265 3685);
DISPLAY INVISIBLE (-3265 3685);
FORCEPROP 1 LASTPIN (-3275 3675) BN 2
J 0
(-3287 3683);
DISPLAY 0.489362 (-3287 3683);
PAINT GREEN (-3287 3683);
FORCEPROP 2 LAST CDS_LIB mstr_standard
J 0
(-3225 3675);
DISPLAY 0.723404 (-3225 3675);
PAINT MONO (-3225 3675);
DISPLAY INVISIBLE (-3225 3675);
FORCEPROP 1 LAST BODY_TYPE PLUMBING
J 0
(-3225 3725);
DISPLAY 0.872340 (-3225 3725);
PAINT GREEN (-3225 3725);
DISPLAY INVISIBLE (-3225 3725);
FORCEPROP 1 LAST HDL_TAP TRUE
J 0
(-2900 3550);
DISPLAY 0.872340 (-2900 3550);
DISPLAY INVISIBLE (-2900 3550);
FORCEPROP 1 LAST PATH I193
J 0
(-3227 3675);
DISPLAY 0.872340 (-3227 3675);
PAINT GREEN (-3227 3675);
DISPLAY INVISIBLE (-3227 3675);
FORCEADD TAP..1
(-3225 3775);
FORCEPROP 3 LASTPIN (-3275 3775) SIG_NAME M_H_CPU1_SA_DQS_DN<3>
J 0
(-3265 3785);
DISPLAY 0.659574 (-3265 3785);
PAINT MONO (-3265 3785);
DISPLAY INVISIBLE (-3265 3785);
FORCEPROP 1 LASTPIN (-3275 3775) BN 3
J 0
(-3287 3783);
DISPLAY 0.489362 (-3287 3783);
PAINT GREEN (-3287 3783);
FORCEPROP 2 LAST CDS_LIB mstr_standard
J 0
(-3225 3775);
DISPLAY 0.723404 (-3225 3775);
PAINT MONO (-3225 3775);
DISPLAY INVISIBLE (-3225 3775);
FORCEPROP 1 LAST BODY_TYPE PLUMBING
J 0
(-3225 3825);
DISPLAY 0.872340 (-3225 3825);
PAINT GREEN (-3225 3825);
DISPLAY INVISIBLE (-3225 3825);
FORCEPROP 1 LAST HDL_TAP TRUE
J 0
(-2900 3650);
DISPLAY 0.872340 (-2900 3650);
DISPLAY INVISIBLE (-2900 3650);
FORCEPROP 1 LAST PATH I194
J 0
(-3227 3775);
DISPLAY 0.872340 (-3227 3775);
PAINT GREEN (-3227 3775);
DISPLAY INVISIBLE (-3227 3775);
FORCEADD TAP..1
(-3425 3925);
FORCEPROP 3 LASTPIN (-3475 3925) SIG_NAME M_H_CPU1_SA_DQS_DP<4>
J 0
(-3465 3935);
DISPLAY 0.659574 (-3465 3935);
PAINT MONO (-3465 3935);
DISPLAY INVISIBLE (-3465 3935);
FORCEPROP 1 LASTPIN (-3475 3925) BN 4
J 0
(-3487 3933);
DISPLAY 0.489362 (-3487 3933);
PAINT GREEN (-3487 3933);
FORCEPROP 2 LAST CDS_LIB mstr_standard
J 0
(-3425 3925);
DISPLAY 0.723404 (-3425 3925);
PAINT MONO (-3425 3925);
DISPLAY INVISIBLE (-3425 3925);
FORCEPROP 1 LAST BODY_TYPE PLUMBING
J 0
(-3425 3975);
DISPLAY 0.872340 (-3425 3975);
PAINT GREEN (-3425 3975);
DISPLAY INVISIBLE (-3425 3975);
FORCEPROP 1 LAST HDL_TAP TRUE
J 0
(-3100 3800);
DISPLAY 0.872340 (-3100 3800);
DISPLAY INVISIBLE (-3100 3800);
FORCEPROP 1 LAST PATH I195
J 0
(-3427 3925);
DISPLAY 0.872340 (-3427 3925);
PAINT GREEN (-3427 3925);
DISPLAY INVISIBLE (-3427 3925);
FORCEADD TAP..1
(-3425 4025);
FORCEPROP 3 LASTPIN (-3475 4025) SIG_NAME M_H_CPU1_SA_DQS_DP<5>
J 0
(-3465 4035);
DISPLAY 0.659574 (-3465 4035);
PAINT MONO (-3465 4035);
DISPLAY INVISIBLE (-3465 4035);
FORCEPROP 1 LASTPIN (-3475 4025) BN 5
J 0
(-3487 4033);
DISPLAY 0.489362 (-3487 4033);
PAINT GREEN (-3487 4033);
FORCEPROP 2 LAST CDS_LIB mstr_standard
J 0
(-3425 4025);
DISPLAY 0.723404 (-3425 4025);
PAINT MONO (-3425 4025);
DISPLAY INVISIBLE (-3425 4025);
FORCEPROP 1 LAST BODY_TYPE PLUMBING
J 0
(-3425 4075);
DISPLAY 0.872340 (-3425 4075);
PAINT GREEN (-3425 4075);
DISPLAY INVISIBLE (-3425 4075);
FORCEPROP 1 LAST HDL_TAP TRUE
J 0
(-3100 3900);
DISPLAY 0.872340 (-3100 3900);
DISPLAY INVISIBLE (-3100 3900);
FORCEPROP 1 LAST PATH I196
J 0
(-3427 4025);
DISPLAY 0.872340 (-3427 4025);
PAINT GREEN (-3427 4025);
DISPLAY INVISIBLE (-3427 4025);
FORCEADD OFFPAGE..2
(-2425 4475);
FORCEPROP 2 LAST $XR0 44 
J 0
(-2236 4475);
DISPLAY 0.638298 (-2236 4475);
PAINT MONO (-2236 4475);
FORCEPROP 2 LAST CDS_LIB mstr_standard
J 0
(-2425 4475);
DISPLAY 0.723404 (-2425 4475);
PAINT MONO (-2425 4475);
DISPLAY INVISIBLE (-2425 4475);
FORCEPROP 1 LAST OFFPAGE TRUE
J 0
(-2100 4350);
DISPLAY 0.723404 (-2100 4350);
PAINT GREEN (-2100 4350);
DISPLAY INVISIBLE (-2100 4350);
FORCEPROP 1 LAST COMMENT_BODY TRUE
J 0
(-2470 4380);
DISPLAY 0.872340 (-2470 4380);
PAINT GREEN (-2470 4380);
DISPLAY INVISIBLE (-2470 4380);
FORCEPROP 2 LAST PATH I198
J 0
(-2225 4525);
DISPLAY 0.680851 (-2225 4525);
DISPLAY INVISIBLE (-2225 4525);
FORCEADD OFFPAGE..2
(-2425 4425);
FORCEPROP 2 LAST $XR0 44 
J 0
(-2236 4425);
DISPLAY 0.638298 (-2236 4425);
PAINT MONO (-2236 4425);
FORCEPROP 2 LAST CDS_LIB mstr_standard
J 0
(-2425 4425);
DISPLAY 0.723404 (-2425 4425);
PAINT MONO (-2425 4425);
DISPLAY INVISIBLE (-2425 4425);
FORCEPROP 1 LAST OFFPAGE TRUE
J 0
(-2100 4300);
DISPLAY 0.723404 (-2100 4300);
PAINT GREEN (-2100 4300);
DISPLAY INVISIBLE (-2100 4300);
FORCEPROP 1 LAST COMMENT_BODY TRUE
J 0
(-2470 4330);
DISPLAY 0.872340 (-2470 4330);
PAINT GREEN (-2470 4330);
DISPLAY INVISIBLE (-2470 4330);
FORCEPROP 2 LAST PATH I199
J 0
(-2225 4475);
DISPLAY 0.680851 (-2225 4475);
DISPLAY INVISIBLE (-2225 4475);
FORCEADD OFFPAGE..5
(-8250 1950);
FORCEPROP 2 LAST $XR0 44 
J 0
(-8474 1950);
DISPLAY 0.638298 (-8474 1950);
PAINT MONO (-8474 1950);
FORCEPROP 2 LAST CDS_LIB mstr_standard
J 0
(-8250 1950);
DISPLAY 0.808511 (-8250 1950);
DISPLAY INVISIBLE (-8250 1950);
FORCEPROP 1 LAST OFFPAGE TRUE
J 0
(-7925 1825);
DISPLAY 0.872340 (-7925 1825);
PAINT GREEN (-7925 1825);
DISPLAY INVISIBLE (-7925 1825);
FORCEPROP 1 LAST COMMENT_BODY TRUE
J 0
(-8150 1875);
DISPLAY 0.872340 (-8150 1875);
PAINT GREEN (-8150 1875);
DISPLAY INVISIBLE (-8150 1875);
FORCEPROP 2 LAST PATH I2
J 0
(-8500 2000);
DISPLAY 1.021277 (-8500 2000);
DISPLAY INVISIBLE (-8500 2000);
FORCEADD OFFPAGE..1
(-8250 5050);
FORCEPROP 2 LAST $XR0 44 
J 0
(-8501 5050);
DISPLAY 0.638298 (-8501 5050);
PAINT MONO (-8501 5050);
FORCEPROP 2 LAST CDS_LIB mstr_standard
J 0
(-8250 5050);
DISPLAY 0.723404 (-8250 5050);
PAINT MONO (-8250 5050);
DISPLAY INVISIBLE (-8250 5050);
FORCEPROP 1 LAST OFFPAGE TRUE
J 0
(-7925 4925);
DISPLAY 0.872340 (-7925 4925);
PAINT GREEN (-7925 4925);
DISPLAY INVISIBLE (-7925 4925);
FORCEPROP 1 LAST COMMENT_BODY TRUE
J 0
(-8125 4950);
DISPLAY 0.872340 (-8125 4950);
PAINT GREEN (-8125 4950);
DISPLAY INVISIBLE (-8125 4950);
FORCEPROP 2 LAST PATH I20
J 0
(-8450 5100);
DISPLAY 1.021277 (-8450 5100);
DISPLAY INVISIBLE (-8450 5100);
FORCEADD OFFPAGE..2
(-2425 3425);
FORCEPROP 2 LAST $XR0 44 
J 0
(-2236 3425);
DISPLAY 0.638298 (-2236 3425);
PAINT MONO (-2236 3425);
FORCEPROP 2 LAST CDS_LIB mstr_standard
J 0
(-2425 3425);
DISPLAY 0.723404 (-2425 3425);
PAINT MONO (-2425 3425);
DISPLAY INVISIBLE (-2425 3425);
FORCEPROP 1 LAST OFFPAGE TRUE
J 0
(-2100 3300);
DISPLAY 0.723404 (-2100 3300);
PAINT GREEN (-2100 3300);
DISPLAY INVISIBLE (-2100 3300);
FORCEPROP 1 LAST COMMENT_BODY TRUE
J 0
(-2470 3330);
DISPLAY 0.872340 (-2470 3330);
PAINT GREEN (-2470 3330);
DISPLAY INVISIBLE (-2470 3330);
FORCEPROP 2 LAST PATH I200
J 0
(-2225 3475);
DISPLAY 0.680851 (-2225 3475);
DISPLAY INVISIBLE (-2225 3475);
FORCEADD OFFPAGE..2
(-2425 3375);
FORCEPROP 2 LAST $XR0 44 
J 0
(-2236 3375);
DISPLAY 0.638298 (-2236 3375);
PAINT MONO (-2236 3375);
FORCEPROP 2 LAST CDS_LIB mstr_standard
J 0
(-2425 3375);
DISPLAY 0.723404 (-2425 3375);
PAINT MONO (-2425 3375);
DISPLAY INVISIBLE (-2425 3375);
FORCEPROP 1 LAST OFFPAGE TRUE
J 0
(-2100 3250);
DISPLAY 0.723404 (-2100 3250);
PAINT GREEN (-2100 3250);
DISPLAY INVISIBLE (-2100 3250);
FORCEPROP 1 LAST COMMENT_BODY TRUE
J 0
(-2470 3280);
DISPLAY 0.872340 (-2470 3280);
PAINT GREEN (-2470 3280);
DISPLAY INVISIBLE (-2470 3280);
FORCEPROP 2 LAST PATH I201
J 0
(-2225 3425);
DISPLAY 0.680851 (-2225 3425);
DISPLAY INVISIBLE (-2225 3425);
FORCEADD TAP..1
(-3225 4375);
FORCEPROP 3 LASTPIN (-3275 4375) SIG_NAME M_H_CPU1_SA_DQS_DN<9>
J 0
(-3265 4385);
DISPLAY 0.659574 (-3265 4385);
PAINT MONO (-3265 4385);
DISPLAY INVISIBLE (-3265 4385);
FORCEPROP 1 LASTPIN (-3275 4375) BN 9
J 0
(-3287 4383);
DISPLAY 0.489362 (-3287 4383);
PAINT GREEN (-3287 4383);
FORCEPROP 2 LAST CDS_LIB mstr_standard
J 0
(-3225 4375);
DISPLAY 0.723404 (-3225 4375);
PAINT MONO (-3225 4375);
DISPLAY INVISIBLE (-3225 4375);
FORCEPROP 1 LAST BODY_TYPE PLUMBING
J 0
(-3225 4425);
DISPLAY 0.872340 (-3225 4425);
PAINT GREEN (-3225 4425);
DISPLAY INVISIBLE (-3225 4425);
FORCEPROP 1 LAST HDL_TAP TRUE
J 0
(-2900 4250);
DISPLAY 0.872340 (-2900 4250);
DISPLAY INVISIBLE (-2900 4250);
FORCEPROP 1 LAST PATH I202
J 0
(-3227 4375);
DISPLAY 0.872340 (-3227 4375);
PAINT GREEN (-3227 4375);
DISPLAY INVISIBLE (-3227 4375);
FORCEADD TAP..1
(-3225 4275);
FORCEPROP 3 LASTPIN (-3275 4275) SIG_NAME M_H_CPU1_SA_DQS_DN<8>
J 0
(-3265 4285);
DISPLAY 0.659574 (-3265 4285);
PAINT MONO (-3265 4285);
DISPLAY INVISIBLE (-3265 4285);
FORCEPROP 1 LASTPIN (-3275 4275) BN 8
J 0
(-3287 4283);
DISPLAY 0.489362 (-3287 4283);
PAINT GREEN (-3287 4283);
FORCEPROP 2 LAST CDS_LIB mstr_standard
J 0
(-3225 4275);
DISPLAY 0.723404 (-3225 4275);
PAINT MONO (-3225 4275);
DISPLAY INVISIBLE (-3225 4275);
FORCEPROP 1 LAST BODY_TYPE PLUMBING
J 0
(-3225 4325);
DISPLAY 0.872340 (-3225 4325);
PAINT GREEN (-3225 4325);
DISPLAY INVISIBLE (-3225 4325);
FORCEPROP 1 LAST HDL_TAP TRUE
J 0
(-2900 4150);
DISPLAY 0.872340 (-2900 4150);
DISPLAY INVISIBLE (-2900 4150);
FORCEPROP 1 LAST PATH I203
J 0
(-3227 4275);
DISPLAY 0.872340 (-3227 4275);
PAINT GREEN (-3227 4275);
DISPLAY INVISIBLE (-3227 4275);
FORCEADD TAP..1
(-3425 4425);
FORCEPROP 3 LASTPIN (-3475 4425) SIG_NAME M_H_CPU1_SA_DQS_DP<9>
J 0
(-3465 4435);
DISPLAY 0.659574 (-3465 4435);
PAINT MONO (-3465 4435);
DISPLAY INVISIBLE (-3465 4435);
FORCEPROP 1 LASTPIN (-3475 4425) BN 9
J 0
(-3487 4433);
DISPLAY 0.489362 (-3487 4433);
PAINT GREEN (-3487 4433);
FORCEPROP 2 LAST CDS_LIB mstr_standard
J 0
(-3425 4425);
DISPLAY 0.723404 (-3425 4425);
PAINT MONO (-3425 4425);
DISPLAY INVISIBLE (-3425 4425);
FORCEPROP 1 LAST BODY_TYPE PLUMBING
J 0
(-3425 4475);
DISPLAY 0.872340 (-3425 4475);
PAINT GREEN (-3425 4475);
DISPLAY INVISIBLE (-3425 4475);
FORCEPROP 1 LAST HDL_TAP TRUE
J 0
(-3100 4300);
DISPLAY 0.872340 (-3100 4300);
DISPLAY INVISIBLE (-3100 4300);
FORCEPROP 1 LAST PATH I204
J 0
(-3427 4425);
DISPLAY 0.872340 (-3427 4425);
PAINT GREEN (-3427 4425);
DISPLAY INVISIBLE (-3427 4425);
FORCEADD TAP..1
(-3425 4325);
FORCEPROP 3 LASTPIN (-3475 4325) SIG_NAME M_H_CPU1_SA_DQS_DP<8>
J 0
(-3465 4335);
DISPLAY 0.659574 (-3465 4335);
PAINT MONO (-3465 4335);
DISPLAY INVISIBLE (-3465 4335);
FORCEPROP 1 LASTPIN (-3475 4325) BN 8
J 0
(-3487 4333);
DISPLAY 0.489362 (-3487 4333);
PAINT GREEN (-3487 4333);
FORCEPROP 2 LAST CDS_LIB mstr_standard
J 0
(-3425 4325);
DISPLAY 0.723404 (-3425 4325);
PAINT MONO (-3425 4325);
DISPLAY INVISIBLE (-3425 4325);
FORCEPROP 1 LAST BODY_TYPE PLUMBING
J 0
(-3425 4375);
DISPLAY 0.872340 (-3425 4375);
PAINT GREEN (-3425 4375);
DISPLAY INVISIBLE (-3425 4375);
FORCEPROP 1 LAST HDL_TAP TRUE
J 0
(-3100 4200);
DISPLAY 0.872340 (-3100 4200);
DISPLAY INVISIBLE (-3100 4200);
FORCEPROP 1 LAST PATH I205
J 0
(-3427 4325);
DISPLAY 0.872340 (-3427 4325);
PAINT GREEN (-3427 4325);
DISPLAY INVISIBLE (-3427 4325);
FORCEADD TAP..1
(-3225 4175);
FORCEPROP 3 LASTPIN (-3275 4175) SIG_NAME M_H_CPU1_SA_DQS_DN<7>
J 0
(-3265 4185);
DISPLAY 0.659574 (-3265 4185);
PAINT MONO (-3265 4185);
DISPLAY INVISIBLE (-3265 4185);
FORCEPROP 1 LASTPIN (-3275 4175) BN 7
J 0
(-3287 4183);
DISPLAY 0.489362 (-3287 4183);
PAINT GREEN (-3287 4183);
FORCEPROP 2 LAST CDS_LIB mstr_standard
J 0
(-3225 4175);
DISPLAY 0.723404 (-3225 4175);
PAINT MONO (-3225 4175);
DISPLAY INVISIBLE (-3225 4175);
FORCEPROP 1 LAST BODY_TYPE PLUMBING
J 0
(-3225 4225);
DISPLAY 0.872340 (-3225 4225);
PAINT GREEN (-3225 4225);
DISPLAY INVISIBLE (-3225 4225);
FORCEPROP 1 LAST HDL_TAP TRUE
J 0
(-2900 4050);
DISPLAY 0.872340 (-2900 4050);
DISPLAY INVISIBLE (-2900 4050);
FORCEPROP 1 LAST PATH I206
J 0
(-3227 4175);
DISPLAY 0.872340 (-3227 4175);
PAINT GREEN (-3227 4175);
DISPLAY INVISIBLE (-3227 4175);
FORCEADD TAP..1
(-3225 4075);
FORCEPROP 3 LASTPIN (-3275 4075) SIG_NAME M_H_CPU1_SA_DQS_DN<6>
J 0
(-3265 4085);
DISPLAY 0.659574 (-3265 4085);
PAINT MONO (-3265 4085);
DISPLAY INVISIBLE (-3265 4085);
FORCEPROP 1 LASTPIN (-3275 4075) BN 6
J 0
(-3287 4083);
DISPLAY 0.489362 (-3287 4083);
PAINT GREEN (-3287 4083);
FORCEPROP 2 LAST CDS_LIB mstr_standard
J 0
(-3225 4075);
DISPLAY 0.723404 (-3225 4075);
PAINT MONO (-3225 4075);
DISPLAY INVISIBLE (-3225 4075);
FORCEPROP 1 LAST BODY_TYPE PLUMBING
J 0
(-3225 4125);
DISPLAY 0.872340 (-3225 4125);
PAINT GREEN (-3225 4125);
DISPLAY INVISIBLE (-3225 4125);
FORCEPROP 1 LAST HDL_TAP TRUE
J 0
(-2900 3950);
DISPLAY 0.872340 (-2900 3950);
DISPLAY INVISIBLE (-2900 3950);
FORCEPROP 1 LAST PATH I207
J 0
(-3227 4075);
DISPLAY 0.872340 (-3227 4075);
PAINT GREEN (-3227 4075);
DISPLAY INVISIBLE (-3227 4075);
FORCEADD TAP..1
(-3225 3975);
FORCEPROP 3 LASTPIN (-3275 3975) SIG_NAME M_H_CPU1_SA_DQS_DN<5>
J 0
(-3265 3985);
DISPLAY 0.659574 (-3265 3985);
PAINT MONO (-3265 3985);
DISPLAY INVISIBLE (-3265 3985);
FORCEPROP 1 LASTPIN (-3275 3975) BN 5
J 0
(-3287 3983);
DISPLAY 0.489362 (-3287 3983);
PAINT GREEN (-3287 3983);
FORCEPROP 2 LAST CDS_LIB mstr_standard
J 0
(-3225 3975);
DISPLAY 0.723404 (-3225 3975);
PAINT MONO (-3225 3975);
DISPLAY INVISIBLE (-3225 3975);
FORCEPROP 1 LAST BODY_TYPE PLUMBING
J 0
(-3225 4025);
DISPLAY 0.872340 (-3225 4025);
PAINT GREEN (-3225 4025);
DISPLAY INVISIBLE (-3225 4025);
FORCEPROP 1 LAST HDL_TAP TRUE
J 0
(-2900 3850);
DISPLAY 0.872340 (-2900 3850);
DISPLAY INVISIBLE (-2900 3850);
FORCEPROP 1 LAST PATH I208
J 0
(-3227 3975);
DISPLAY 0.872340 (-3227 3975);
PAINT GREEN (-3227 3975);
DISPLAY INVISIBLE (-3227 3975);
FORCEADD TAP..1
(-3225 3875);
FORCEPROP 3 LASTPIN (-3275 3875) SIG_NAME M_H_CPU1_SA_DQS_DN<4>
J 0
(-3265 3885);
DISPLAY 0.659574 (-3265 3885);
PAINT MONO (-3265 3885);
DISPLAY INVISIBLE (-3265 3885);
FORCEPROP 1 LASTPIN (-3275 3875) BN 4
J 0
(-3287 3883);
DISPLAY 0.489362 (-3287 3883);
PAINT GREEN (-3287 3883);
FORCEPROP 2 LAST CDS_LIB mstr_standard
J 0
(-3225 3875);
DISPLAY 0.723404 (-3225 3875);
PAINT MONO (-3225 3875);
DISPLAY INVISIBLE (-3225 3875);
FORCEPROP 1 LAST BODY_TYPE PLUMBING
J 0
(-3225 3925);
DISPLAY 0.872340 (-3225 3925);
PAINT GREEN (-3225 3925);
DISPLAY INVISIBLE (-3225 3925);
FORCEPROP 1 LAST HDL_TAP TRUE
J 0
(-2900 3750);
DISPLAY 0.872340 (-2900 3750);
DISPLAY INVISIBLE (-2900 3750);
FORCEPROP 1 LAST PATH I209
J 0
(-3227 3875);
DISPLAY 0.872340 (-3227 3875);
PAINT GREEN (-3227 3875);
DISPLAY INVISIBLE (-3227 3875);
FORCEADD OFFPAGE..1
(-8250 5450);
FORCEPROP 2 LAST $XR0 44 
J 0
(-8501 5450);
DISPLAY 0.638298 (-8501 5450);
PAINT MONO (-8501 5450);
FORCEPROP 2 LAST CDS_LIB mstr_standard
J 0
(-8250 5450);
DISPLAY 0.723404 (-8250 5450);
PAINT MONO (-8250 5450);
DISPLAY INVISIBLE (-8250 5450);
FORCEPROP 1 LAST OFFPAGE TRUE
J 0
(-7925 5325);
DISPLAY 0.872340 (-7925 5325);
PAINT GREEN (-7925 5325);
DISPLAY INVISIBLE (-7925 5325);
FORCEPROP 1 LAST COMMENT_BODY TRUE
J 0
(-8125 5350);
DISPLAY 0.872340 (-8125 5350);
PAINT GREEN (-8125 5350);
DISPLAY INVISIBLE (-8125 5350);
FORCEPROP 2 LAST PATH I21
J 0
(-8450 5500);
DISPLAY 1.021277 (-8450 5500);
DISPLAY INVISIBLE (-8450 5500);
FORCEADD TAP..1
(-3225 3575);
FORCEPROP 3 LASTPIN (-3275 3575) SIG_NAME M_H_CPU1_SA_DQS_DN<1>
J 0
(-3265 3585);
DISPLAY 0.659574 (-3265 3585);
PAINT MONO (-3265 3585);
DISPLAY INVISIBLE (-3265 3585);
FORCEPROP 1 LASTPIN (-3275 3575) BN 1
J 0
(-3287 3583);
DISPLAY 0.489362 (-3287 3583);
PAINT GREEN (-3287 3583);
FORCEPROP 2 LAST CDS_LIB mstr_standard
J 0
(-3225 3575);
DISPLAY 0.723404 (-3225 3575);
PAINT MONO (-3225 3575);
DISPLAY INVISIBLE (-3225 3575);
FORCEPROP 1 LAST BODY_TYPE PLUMBING
J 0
(-3225 3625);
DISPLAY 0.872340 (-3225 3625);
PAINT GREEN (-3225 3625);
DISPLAY INVISIBLE (-3225 3625);
FORCEPROP 1 LAST HDL_TAP TRUE
J 0
(-2900 3450);
DISPLAY 0.872340 (-2900 3450);
DISPLAY INVISIBLE (-2900 3450);
FORCEPROP 1 LAST PATH I210
J 0
(-3227 3575);
DISPLAY 0.872340 (-3227 3575);
PAINT GREEN (-3227 3575);
DISPLAY INVISIBLE (-3227 3575);
FORCEADD TAP..1
(-3225 3475);
FORCEPROP 3 LASTPIN (-3275 3475) SIG_NAME M_H_CPU1_SA_DQS_DN<0>
J 0
(-3265 3485);
DISPLAY 0.659574 (-3265 3485);
PAINT MONO (-3265 3485);
DISPLAY INVISIBLE (-3265 3485);
FORCEPROP 1 LASTPIN (-3275 3475) BN 0
J 0
(-3287 3483);
DISPLAY 0.489362 (-3287 3483);
PAINT GREEN (-3287 3483);
FORCEPROP 2 LAST CDS_LIB mstr_standard
J 0
(-3225 3475);
DISPLAY 0.723404 (-3225 3475);
PAINT MONO (-3225 3475);
DISPLAY INVISIBLE (-3225 3475);
FORCEPROP 1 LAST BODY_TYPE PLUMBING
J 0
(-3225 3525);
DISPLAY 0.872340 (-3225 3525);
PAINT GREEN (-3225 3525);
DISPLAY INVISIBLE (-3225 3525);
FORCEPROP 1 LAST HDL_TAP TRUE
J 0
(-2900 3350);
DISPLAY 0.872340 (-2900 3350);
DISPLAY INVISIBLE (-2900 3350);
FORCEPROP 1 LAST PATH I211
J 0
(-3227 3475);
DISPLAY 0.872340 (-3227 3475);
PAINT GREEN (-3227 3475);
DISPLAY INVISIBLE (-3227 3475);
FORCEADD TAP..1
(-3225 3225);
FORCEPROP 3 LASTPIN (-3275 3225) SIG_NAME M_H_CPU1_SB_DQS_DN<8>
J 0
(-3265 3235);
DISPLAY 0.659574 (-3265 3235);
PAINT MONO (-3265 3235);
DISPLAY INVISIBLE (-3265 3235);
FORCEPROP 1 LASTPIN (-3275 3225) BN 8
J 0
(-3287 3233);
DISPLAY 0.489362 (-3287 3233);
PAINT GREEN (-3287 3233);
FORCEPROP 2 LAST CDS_LIB mstr_standard
J 0
(-3225 3225);
DISPLAY 0.723404 (-3225 3225);
PAINT MONO (-3225 3225);
DISPLAY INVISIBLE (-3225 3225);
FORCEPROP 1 LAST BODY_TYPE PLUMBING
J 0
(-3225 3275);
DISPLAY 0.872340 (-3225 3275);
PAINT GREEN (-3225 3275);
DISPLAY INVISIBLE (-3225 3275);
FORCEPROP 1 LAST HDL_TAP TRUE
J 0
(-2900 3100);
DISPLAY 0.872340 (-2900 3100);
DISPLAY INVISIBLE (-2900 3100);
FORCEPROP 1 LAST PATH I212
J 0
(-3227 3225);
DISPLAY 0.872340 (-3227 3225);
PAINT GREEN (-3227 3225);
DISPLAY INVISIBLE (-3227 3225);
FORCEADD TAP..1
(-3225 3325);
FORCEPROP 3 LASTPIN (-3275 3325) SIG_NAME M_H_CPU1_SB_DQS_DN<9>
J 0
(-3265 3335);
DISPLAY 0.659574 (-3265 3335);
PAINT MONO (-3265 3335);
DISPLAY INVISIBLE (-3265 3335);
FORCEPROP 1 LASTPIN (-3275 3325) BN 9
J 0
(-3287 3333);
DISPLAY 0.489362 (-3287 3333);
PAINT GREEN (-3287 3333);
FORCEPROP 2 LAST CDS_LIB mstr_standard
J 0
(-3225 3325);
DISPLAY 0.723404 (-3225 3325);
PAINT MONO (-3225 3325);
DISPLAY INVISIBLE (-3225 3325);
FORCEPROP 1 LAST BODY_TYPE PLUMBING
J 0
(-3225 3375);
DISPLAY 0.872340 (-3225 3375);
PAINT GREEN (-3225 3375);
DISPLAY INVISIBLE (-3225 3375);
FORCEPROP 1 LAST HDL_TAP TRUE
J 0
(-2900 3200);
DISPLAY 0.872340 (-2900 3200);
DISPLAY INVISIBLE (-2900 3200);
FORCEPROP 1 LAST PATH I213
J 0
(-3227 3325);
DISPLAY 0.872340 (-3227 3325);
PAINT GREEN (-3227 3325);
DISPLAY INVISIBLE (-3227 3325);
FORCEADD TAP..1
(-3425 4225);
FORCEPROP 3 LASTPIN (-3475 4225) SIG_NAME M_H_CPU1_SA_DQS_DP<7>
J 0
(-3465 4235);
DISPLAY 0.659574 (-3465 4235);
PAINT MONO (-3465 4235);
DISPLAY INVISIBLE (-3465 4235);
FORCEPROP 1 LASTPIN (-3475 4225) BN 7
J 0
(-3487 4233);
DISPLAY 0.489362 (-3487 4233);
PAINT GREEN (-3487 4233);
FORCEPROP 2 LAST CDS_LIB mstr_standard
J 0
(-3425 4225);
DISPLAY 0.723404 (-3425 4225);
PAINT MONO (-3425 4225);
DISPLAY INVISIBLE (-3425 4225);
FORCEPROP 1 LAST BODY_TYPE PLUMBING
J 0
(-3425 4275);
DISPLAY 0.872340 (-3425 4275);
PAINT GREEN (-3425 4275);
DISPLAY INVISIBLE (-3425 4275);
FORCEPROP 1 LAST HDL_TAP TRUE
J 0
(-3100 4100);
DISPLAY 0.872340 (-3100 4100);
DISPLAY INVISIBLE (-3100 4100);
FORCEPROP 1 LAST PATH I214
J 0
(-3427 4225);
DISPLAY 0.872340 (-3427 4225);
PAINT GREEN (-3427 4225);
DISPLAY INVISIBLE (-3427 4225);
FORCEADD TAP..1
(-3425 4125);
FORCEPROP 3 LASTPIN (-3475 4125) SIG_NAME M_H_CPU1_SA_DQS_DP<6>
J 0
(-3465 4135);
DISPLAY 0.659574 (-3465 4135);
PAINT MONO (-3465 4135);
DISPLAY INVISIBLE (-3465 4135);
FORCEPROP 1 LASTPIN (-3475 4125) BN 6
J 0
(-3487 4133);
DISPLAY 0.489362 (-3487 4133);
PAINT GREEN (-3487 4133);
FORCEPROP 2 LAST CDS_LIB mstr_standard
J 0
(-3425 4125);
DISPLAY 0.723404 (-3425 4125);
PAINT MONO (-3425 4125);
DISPLAY INVISIBLE (-3425 4125);
FORCEPROP 1 LAST BODY_TYPE PLUMBING
J 0
(-3425 4175);
DISPLAY 0.872340 (-3425 4175);
PAINT GREEN (-3425 4175);
DISPLAY INVISIBLE (-3425 4175);
FORCEPROP 1 LAST HDL_TAP TRUE
J 0
(-3100 4000);
DISPLAY 0.872340 (-3100 4000);
DISPLAY INVISIBLE (-3100 4000);
FORCEPROP 1 LAST PATH I215
J 0
(-3427 4125);
DISPLAY 0.872340 (-3427 4125);
PAINT GREEN (-3427 4125);
DISPLAY INVISIBLE (-3427 4125);
FORCEADD TAP..1
(-3425 3825);
FORCEPROP 3 LASTPIN (-3475 3825) SIG_NAME M_H_CPU1_SA_DQS_DP<3>
J 0
(-3465 3835);
DISPLAY 0.659574 (-3465 3835);
PAINT MONO (-3465 3835);
DISPLAY INVISIBLE (-3465 3835);
FORCEPROP 1 LASTPIN (-3475 3825) BN 3
J 0
(-3487 3833);
DISPLAY 0.489362 (-3487 3833);
PAINT GREEN (-3487 3833);
FORCEPROP 2 LAST CDS_LIB mstr_standard
J 0
(-3425 3825);
DISPLAY 0.723404 (-3425 3825);
PAINT MONO (-3425 3825);
DISPLAY INVISIBLE (-3425 3825);
FORCEPROP 1 LAST BODY_TYPE PLUMBING
J 0
(-3425 3875);
DISPLAY 0.872340 (-3425 3875);
PAINT GREEN (-3425 3875);
DISPLAY INVISIBLE (-3425 3875);
FORCEPROP 1 LAST HDL_TAP TRUE
J 0
(-3100 3700);
DISPLAY 0.872340 (-3100 3700);
DISPLAY INVISIBLE (-3100 3700);
FORCEPROP 1 LAST PATH I216
J 0
(-3427 3825);
DISPLAY 0.872340 (-3427 3825);
PAINT GREEN (-3427 3825);
DISPLAY INVISIBLE (-3427 3825);
FORCEADD TAP..1
(-3425 3725);
FORCEPROP 3 LASTPIN (-3475 3725) SIG_NAME M_H_CPU1_SA_DQS_DP<2>
J 0
(-3465 3735);
DISPLAY 0.659574 (-3465 3735);
PAINT MONO (-3465 3735);
DISPLAY INVISIBLE (-3465 3735);
FORCEPROP 1 LASTPIN (-3475 3725) BN 2
J 0
(-3487 3733);
DISPLAY 0.489362 (-3487 3733);
PAINT GREEN (-3487 3733);
FORCEPROP 2 LAST CDS_LIB mstr_standard
J 0
(-3425 3725);
DISPLAY 0.723404 (-3425 3725);
PAINT MONO (-3425 3725);
DISPLAY INVISIBLE (-3425 3725);
FORCEPROP 1 LAST BODY_TYPE PLUMBING
J 0
(-3425 3775);
DISPLAY 0.872340 (-3425 3775);
PAINT GREEN (-3425 3775);
DISPLAY INVISIBLE (-3425 3775);
FORCEPROP 1 LAST HDL_TAP TRUE
J 0
(-3100 3600);
DISPLAY 0.872340 (-3100 3600);
DISPLAY INVISIBLE (-3100 3600);
FORCEPROP 1 LAST PATH I217
J 0
(-3427 3725);
DISPLAY 0.872340 (-3427 3725);
PAINT GREEN (-3427 3725);
DISPLAY INVISIBLE (-3427 3725);
FORCEADD TAP..1
(-3425 3625);
FORCEPROP 3 LASTPIN (-3475 3625) SIG_NAME M_H_CPU1_SA_DQS_DP<1>
J 0
(-3465 3635);
DISPLAY 0.659574 (-3465 3635);
PAINT MONO (-3465 3635);
DISPLAY INVISIBLE (-3465 3635);
FORCEPROP 1 LASTPIN (-3475 3625) BN 1
J 0
(-3487 3633);
DISPLAY 0.489362 (-3487 3633);
PAINT GREEN (-3487 3633);
FORCEPROP 2 LAST CDS_LIB mstr_standard
J 0
(-3425 3625);
DISPLAY 0.723404 (-3425 3625);
PAINT MONO (-3425 3625);
DISPLAY INVISIBLE (-3425 3625);
FORCEPROP 1 LAST BODY_TYPE PLUMBING
J 0
(-3425 3675);
DISPLAY 0.872340 (-3425 3675);
PAINT GREEN (-3425 3675);
DISPLAY INVISIBLE (-3425 3675);
FORCEPROP 1 LAST HDL_TAP TRUE
J 0
(-3100 3500);
DISPLAY 0.872340 (-3100 3500);
DISPLAY INVISIBLE (-3100 3500);
FORCEPROP 1 LAST PATH I218
J 0
(-3427 3625);
DISPLAY 0.872340 (-3427 3625);
PAINT GREEN (-3427 3625);
DISPLAY INVISIBLE (-3427 3625);
FORCEADD TAP..1
(-3425 3525);
FORCEPROP 3 LASTPIN (-3475 3525) SIG_NAME M_H_CPU1_SA_DQS_DP<0>
J 0
(-3465 3535);
DISPLAY 0.659574 (-3465 3535);
PAINT MONO (-3465 3535);
DISPLAY INVISIBLE (-3465 3535);
FORCEPROP 1 LASTPIN (-3475 3525) BN 0
J 0
(-3487 3533);
DISPLAY 0.489362 (-3487 3533);
PAINT GREEN (-3487 3533);
FORCEPROP 2 LAST CDS_LIB mstr_standard
J 0
(-3425 3525);
DISPLAY 0.723404 (-3425 3525);
PAINT MONO (-3425 3525);
DISPLAY INVISIBLE (-3425 3525);
FORCEPROP 1 LAST BODY_TYPE PLUMBING
J 0
(-3425 3575);
DISPLAY 0.872340 (-3425 3575);
PAINT GREEN (-3425 3575);
DISPLAY INVISIBLE (-3425 3575);
FORCEPROP 1 LAST HDL_TAP TRUE
J 0
(-3100 3400);
DISPLAY 0.872340 (-3100 3400);
DISPLAY INVISIBLE (-3100 3400);
FORCEPROP 1 LAST PATH I219
J 0
(-3427 3525);
DISPLAY 0.872340 (-3427 3525);
PAINT GREEN (-3427 3525);
DISPLAY INVISIBLE (-3427 3525);
FORCEADD SCONN288_DDR506112002KQ..1
(-6800 3650);
FORCEPROP 1 LAST LOCATION J27
J 0
(-7250 5725);
DISPLAY 0.468085 (-7250 5725);
PAINT SKYBLUE (-7250 5725);
FORCEPROP 0 LAST $SEC 1
J 0
(-7250 5875);
DISPLAY 0.680851 (-7250 5875);
PAINT MONO (-7250 5875);
DISPLAY INVISIBLE (-7250 5875);
FORCEPROP 2 LAST CDS_SEC 1
J 0
(-7250 5875);
DISPLAY 1.021277 (-7250 5875);
DISPLAY INVISIBLE (-7250 5875);
FORCEPROP 0 LASTPIN (-7400 3050) $PN 62
J 2
(-7410 3060);
DISPLAY 0.680851 (-7410 3060);
PAINT MONO (-7410 3060);
FORCEPROP 0 LASTPIN (-7400 5100) $PN 66
J 2
(-7410 5110);
DISPLAY 0.680851 (-7410 5110);
PAINT MONO (-7410 5110);
FORCEPROP 0 LASTPIN (-7400 4700) $PN 76
J 2
(-7410 4710);
DISPLAY 0.680851 (-7410 4710);
PAINT MONO (-7410 4710);
FORCEPROP 0 LASTPIN (-7400 5150) $PN 211
J 2
(-7410 5160);
DISPLAY 0.680851 (-7410 5160);
PAINT MONO (-7410 5160);
FORCEPROP 0 LASTPIN (-7400 4750) $PN 221
J 2
(-7410 4760);
DISPLAY 0.680851 (-7410 4760);
PAINT MONO (-7410 4760);
FORCEPROP 0 LASTPIN (-7400 5200) $PN 68
J 2
(-7410 5210);
DISPLAY 0.680851 (-7410 5210);
PAINT MONO (-7410 5210);
FORCEPROP 0 LASTPIN (-7400 4800) $PN 78
J 2
(-7410 4810);
DISPLAY 0.680851 (-7410 4810);
PAINT MONO (-7410 4810);
FORCEPROP 0 LASTPIN (-7400 5250) $PN 213
J 2
(-7410 5260);
DISPLAY 0.680851 (-7410 5260);
PAINT MONO (-7410 5260);
FORCEPROP 0 LASTPIN (-7400 4850) $PN 223
J 2
(-7410 4860);
DISPLAY 0.680851 (-7410 4860);
PAINT MONO (-7410 4860);
FORCEPROP 0 LASTPIN (-7400 5300) $PN 70
J 2
(-7410 5310);
DISPLAY 0.680851 (-7410 5310);
PAINT MONO (-7410 5310);
FORCEPROP 0 LASTPIN (-7400 4900) $PN 80
J 2
(-7410 4910);
DISPLAY 0.680851 (-7410 4910);
PAINT MONO (-7410 4910);
FORCEPROP 0 LASTPIN (-7400 5350) $PN 215
J 2
(-7410 5360);
DISPLAY 0.680851 (-7410 5360);
PAINT MONO (-7410 5360);
FORCEPROP 0 LASTPIN (-7400 4950) $PN 225
J 2
(-7410 4960);
DISPLAY 0.680851 (-7410 4960);
PAINT MONO (-7410 4960);
FORCEPROP 0 LASTPIN (-7400 5400) $PN 72
J 2
(-7410 5410);
DISPLAY 0.680851 (-7410 5410);
PAINT MONO (-7410 5410);
FORCEPROP 0 LASTPIN (-7400 5000) $PN 82
J 2
(-7410 5010);
DISPLAY 0.680851 (-7410 5010);
PAINT MONO (-7410 5010);
FORCEPROP 0 LASTPIN (-7400 3650) $PN 51
J 2
(-7410 3660);
DISPLAY 0.680851 (-7410 3660);
PAINT MONO (-7410 3660);
FORCEPROP 0 LASTPIN (-7400 3200) $PN 96
J 2
(-7410 3210);
DISPLAY 0.680851 (-7410 3210);
PAINT MONO (-7410 3210);
FORCEPROP 0 LASTPIN (-7400 3700) $PN 53
J 2
(-7410 3710);
DISPLAY 0.680851 (-7410 3710);
PAINT MONO (-7410 3710);
FORCEPROP 0 LASTPIN (-7400 3250) $PN 98
J 2
(-7410 3260);
DISPLAY 0.680851 (-7410 3260);
PAINT MONO (-7410 3260);
FORCEPROP 0 LASTPIN (-7400 3750) $PN 196
J 2
(-7410 3760);
DISPLAY 0.680851 (-7410 3760);
PAINT MONO (-7410 3760);
FORCEPROP 0 LASTPIN (-7400 3300) $PN 241
J 2
(-7410 3310);
DISPLAY 0.680851 (-7410 3310);
PAINT MONO (-7410 3310);
FORCEPROP 0 LASTPIN (-7400 3800) $PN 198
J 2
(-7410 3810);
DISPLAY 0.680851 (-7410 3810);
PAINT MONO (-7410 3810);
FORCEPROP 0 LASTPIN (-7400 3350) $PN 243
J 2
(-7410 3360);
DISPLAY 0.680851 (-7410 3360);
PAINT MONO (-7410 3360);
FORCEPROP 0 LASTPIN (-7400 3850) $PN 58
J 2
(-7410 3860);
DISPLAY 0.680851 (-7410 3860);
PAINT MONO (-7410 3860);
FORCEPROP 0 LASTPIN (-7400 3400) $PN 89
J 2
(-7410 3410);
DISPLAY 0.680851 (-7410 3410);
PAINT MONO (-7410 3410);
FORCEPROP 0 LASTPIN (-7400 3900) $PN 60
J 2
(-7410 3910);
DISPLAY 0.680851 (-7410 3910);
PAINT MONO (-7410 3910);
FORCEPROP 0 LASTPIN (-7400 3450) $PN 91
J 2
(-7410 3460);
DISPLAY 0.680851 (-7410 3460);
PAINT MONO (-7410 3460);
FORCEPROP 0 LASTPIN (-7400 3950) $PN 203
J 2
(-7410 3960);
DISPLAY 0.680851 (-7410 3960);
PAINT MONO (-7410 3960);
FORCEPROP 0 LASTPIN (-7400 3500) $PN 234
J 2
(-7410 3510);
DISPLAY 0.680851 (-7410 3510);
PAINT MONO (-7410 3510);
FORCEPROP 0 LASTPIN (-7400 4000) $PN 205
J 2
(-7410 4010);
DISPLAY 0.680851 (-7410 4010);
PAINT MONO (-7410 4010);
FORCEPROP 0 LASTPIN (-7400 3550) $PN 236
J 2
(-7410 3560);
DISPLAY 0.680851 (-7410 3560);
PAINT MONO (-7410 3560);
FORCEPROP 0 LASTPIN (-7400 4100) $PN 218
J 2
(-7410 4110);
DISPLAY 0.680851 (-7410 4110);
PAINT MONO (-7410 4110);
FORCEPROP 0 LASTPIN (-7400 4150) $PN 217
J 2
(-7410 4160);
DISPLAY 0.680851 (-7410 4160);
PAINT MONO (-7410 4160);
FORCEPROP 0 LASTPIN (-7400 4400) $PN 64
J 2
(-7410 4410);
DISPLAY 0.680851 (-7410 4410);
PAINT MONO (-7410 4410);
FORCEPROP 0 LASTPIN (-7400 4250) $PN 84
J 2
(-7410 4260);
DISPLAY 0.680851 (-7410 4260);
PAINT MONO (-7410 4260);
FORCEPROP 0 LASTPIN (-7400 4450) $PN 209
J 2
(-7410 4460);
DISPLAY 0.680851 (-7410 4460);
PAINT MONO (-7410 4460);
FORCEPROP 0 LASTPIN (-7400 4300) $PN 229
J 2
(-7410 4310);
DISPLAY 0.680851 (-7410 4310);
PAINT MONO (-7410 4310);
FORCEPROP 0 LASTPIN (-6200 3850) $PN 7
J 0
(-6190 3860);
DISPLAY 0.680851 (-6190 3860);
PAINT MONO (-6190 3860);
FORCEPROP 0 LASTPIN (-6200 2200) $PN 100
J 0
(-6190 2210);
DISPLAY 0.680851 (-6190 2210);
PAINT MONO (-6190 2210);
FORCEPROP 0 LASTPIN (-6200 3900) $PN 9
J 0
(-6190 3910);
DISPLAY 0.680851 (-6190 3910);
PAINT MONO (-6190 3910);
FORCEPROP 0 LASTPIN (-6200 2250) $PN 102
J 0
(-6190 2260);
DISPLAY 0.680851 (-6190 2260);
PAINT MONO (-6190 2260);
FORCEPROP 0 LASTPIN (-6200 3950) $PN 152
J 0
(-6190 3960);
DISPLAY 0.680851 (-6190 3960);
PAINT MONO (-6190 3960);
FORCEPROP 0 LASTPIN (-6200 2300) $PN 245
J 0
(-6190 2310);
DISPLAY 0.680851 (-6190 2310);
PAINT MONO (-6190 2310);
FORCEPROP 0 LASTPIN (-6200 4000) $PN 154
J 0
(-6190 4010);
DISPLAY 0.680851 (-6190 4010);
PAINT MONO (-6190 4010);
FORCEPROP 0 LASTPIN (-6200 2350) $PN 247
J 0
(-6190 2360);
DISPLAY 0.680851 (-6190 2360);
PAINT MONO (-6190 2360);
FORCEPROP 0 LASTPIN (-6200 4050) $PN 14
J 0
(-6190 4060);
DISPLAY 0.680851 (-6190 4060);
PAINT MONO (-6190 4060);
FORCEPROP 0 LASTPIN (-6200 2400) $PN 107
J 0
(-6190 2410);
DISPLAY 0.680851 (-6190 2410);
PAINT MONO (-6190 2410);
FORCEPROP 0 LASTPIN (-6200 4100) $PN 16
J 0
(-6190 4110);
DISPLAY 0.680851 (-6190 4110);
PAINT MONO (-6190 4110);
FORCEPROP 0 LASTPIN (-6200 2450) $PN 109
J 0
(-6190 2460);
DISPLAY 0.680851 (-6190 2460);
PAINT MONO (-6190 2460);
FORCEPROP 0 LASTPIN (-6200 4150) $PN 159
J 0
(-6190 4160);
DISPLAY 0.680851 (-6190 4160);
PAINT MONO (-6190 4160);
FORCEPROP 0 LASTPIN (-6200 2500) $PN 252
J 0
(-6190 2510);
DISPLAY 0.680851 (-6190 2510);
PAINT MONO (-6190 2510);
FORCEPROP 0 LASTPIN (-6200 4200) $PN 161
J 0
(-6190 4210);
DISPLAY 0.680851 (-6190 4210);
PAINT MONO (-6190 4210);
FORCEPROP 0 LASTPIN (-6200 2550) $PN 254
J 0
(-6190 2560);
DISPLAY 0.680851 (-6190 2560);
PAINT MONO (-6190 2560);
FORCEPROP 0 LASTPIN (-6200 4250) $PN 18
J 0
(-6190 4260);
DISPLAY 0.680851 (-6190 4260);
PAINT MONO (-6190 4260);
FORCEPROP 0 LASTPIN (-6200 2600) $PN 111
J 0
(-6190 2610);
DISPLAY 0.680851 (-6190 2610);
PAINT MONO (-6190 2610);
FORCEPROP 0 LASTPIN (-6200 4300) $PN 20
J 0
(-6190 4310);
DISPLAY 0.680851 (-6190 4310);
PAINT MONO (-6190 4310);
FORCEPROP 0 LASTPIN (-6200 2650) $PN 113
J 0
(-6190 2660);
DISPLAY 0.680851 (-6190 2660);
PAINT MONO (-6190 2660);
FORCEPROP 0 LASTPIN (-6200 4350) $PN 163
J 0
(-6190 4360);
DISPLAY 0.680851 (-6190 4360);
PAINT MONO (-6190 4360);
FORCEPROP 0 LASTPIN (-6200 2700) $PN 256
J 0
(-6190 2710);
DISPLAY 0.680851 (-6190 2710);
PAINT MONO (-6190 2710);
FORCEPROP 0 LASTPIN (-6200 4400) $PN 165
J 0
(-6190 4410);
DISPLAY 0.680851 (-6190 4410);
PAINT MONO (-6190 4410);
FORCEPROP 0 LASTPIN (-6200 2750) $PN 258
J 0
(-6190 2760);
DISPLAY 0.680851 (-6190 2760);
PAINT MONO (-6190 2760);
FORCEPROP 0 LASTPIN (-6200 4450) $PN 25
J 0
(-6190 4460);
DISPLAY 0.680851 (-6190 4460);
PAINT MONO (-6190 4460);
FORCEPROP 0 LASTPIN (-6200 2800) $PN 118
J 0
(-6190 2810);
DISPLAY 0.680851 (-6190 2810);
PAINT MONO (-6190 2810);
FORCEPROP 0 LASTPIN (-6200 4500) $PN 27
J 0
(-6190 4510);
DISPLAY 0.680851 (-6190 4510);
PAINT MONO (-6190 4510);
FORCEPROP 0 LASTPIN (-6200 2850) $PN 120
J 0
(-6190 2860);
DISPLAY 0.680851 (-6190 2860);
PAINT MONO (-6190 2860);
FORCEPROP 0 LASTPIN (-6200 4550) $PN 170
J 0
(-6190 4560);
DISPLAY 0.680851 (-6190 4560);
PAINT MONO (-6190 4560);
FORCEPROP 0 LASTPIN (-6200 2900) $PN 263
J 0
(-6190 2910);
DISPLAY 0.680851 (-6190 2910);
PAINT MONO (-6190 2910);
FORCEPROP 0 LASTPIN (-6200 4600) $PN 172
J 0
(-6190 4610);
DISPLAY 0.680851 (-6190 4610);
PAINT MONO (-6190 4610);
FORCEPROP 0 LASTPIN (-6200 2950) $PN 265
J 0
(-6190 2960);
DISPLAY 0.680851 (-6190 2960);
PAINT MONO (-6190 2960);
FORCEPROP 0 LASTPIN (-6200 4650) $PN 29
J 0
(-6190 4660);
DISPLAY 0.680851 (-6190 4660);
PAINT MONO (-6190 4660);
FORCEPROP 0 LASTPIN (-6200 3000) $PN 122
J 0
(-6190 3010);
DISPLAY 0.680851 (-6190 3010);
PAINT MONO (-6190 3010);
FORCEPROP 0 LASTPIN (-6200 4700) $PN 31
J 0
(-6190 4710);
DISPLAY 0.680851 (-6190 4710);
PAINT MONO (-6190 4710);
FORCEPROP 0 LASTPIN (-6200 3050) $PN 124
J 0
(-6190 3060);
DISPLAY 0.680851 (-6190 3060);
PAINT MONO (-6190 3060);
FORCEPROP 0 LASTPIN (-6200 4750) $PN 174
J 0
(-6190 4760);
DISPLAY 0.680851 (-6190 4760);
PAINT MONO (-6190 4760);
FORCEPROP 0 LASTPIN (-6200 3100) $PN 267
J 0
(-6190 3110);
DISPLAY 0.680851 (-6190 3110);
PAINT MONO (-6190 3110);
FORCEPROP 0 LASTPIN (-6200 4800) $PN 176
J 0
(-6190 4810);
DISPLAY 0.680851 (-6190 4810);
PAINT MONO (-6190 4810);
FORCEPROP 0 LASTPIN (-6200 3150) $PN 269
J 0
(-6190 3160);
DISPLAY 0.680851 (-6190 3160);
PAINT MONO (-6190 3160);
FORCEPROP 0 LASTPIN (-6200 4850) $PN 36
J 0
(-6190 4860);
DISPLAY 0.680851 (-6190 4860);
PAINT MONO (-6190 4860);
FORCEPROP 0 LASTPIN (-6200 3200) $PN 129
J 0
(-6190 3210);
DISPLAY 0.680851 (-6190 3210);
PAINT MONO (-6190 3210);
FORCEPROP 0 LASTPIN (-6200 4900) $PN 38
J 0
(-6190 4910);
DISPLAY 0.680851 (-6190 4910);
PAINT MONO (-6190 4910);
FORCEPROP 0 LASTPIN (-6200 3250) $PN 131
J 0
(-6190 3260);
DISPLAY 0.680851 (-6190 3260);
PAINT MONO (-6190 3260);
FORCEPROP 0 LASTPIN (-6200 4950) $PN 181
J 0
(-6190 4960);
DISPLAY 0.680851 (-6190 4960);
PAINT MONO (-6190 4960);
FORCEPROP 0 LASTPIN (-6200 3300) $PN 274
J 0
(-6190 3310);
DISPLAY 0.680851 (-6190 3310);
PAINT MONO (-6190 3310);
FORCEPROP 0 LASTPIN (-6200 5000) $PN 183
J 0
(-6190 5010);
DISPLAY 0.680851 (-6190 5010);
PAINT MONO (-6190 5010);
FORCEPROP 0 LASTPIN (-6200 3350) $PN 276
J 0
(-6190 3360);
DISPLAY 0.680851 (-6190 3360);
PAINT MONO (-6190 3360);
FORCEPROP 0 LASTPIN (-6200 5050) $PN 40
J 0
(-6190 5060);
DISPLAY 0.680851 (-6190 5060);
PAINT MONO (-6190 5060);
FORCEPROP 0 LASTPIN (-6200 3400) $PN 133
J 0
(-6190 3410);
DISPLAY 0.680851 (-6190 3410);
PAINT MONO (-6190 3410);
FORCEPROP 0 LASTPIN (-6200 5100) $PN 42
J 0
(-6190 5110);
DISPLAY 0.680851 (-6190 5110);
PAINT MONO (-6190 5110);
FORCEPROP 0 LASTPIN (-6200 3450) $PN 135
J 0
(-6190 3460);
DISPLAY 0.680851 (-6190 3460);
PAINT MONO (-6190 3460);
FORCEPROP 0 LASTPIN (-6200 5150) $PN 185
J 0
(-6190 5160);
DISPLAY 0.680851 (-6190 5160);
PAINT MONO (-6190 5160);
FORCEPROP 0 LASTPIN (-6200 3500) $PN 278
J 0
(-6190 3510);
DISPLAY 0.680851 (-6190 3510);
PAINT MONO (-6190 3510);
FORCEPROP 0 LASTPIN (-6200 5200) $PN 187
J 0
(-6190 5210);
DISPLAY 0.680851 (-6190 5210);
PAINT MONO (-6190 5210);
FORCEPROP 0 LASTPIN (-6200 3550) $PN 280
J 0
(-6190 3560);
DISPLAY 0.680851 (-6190 3560);
PAINT MONO (-6190 3560);
FORCEPROP 0 LASTPIN (-6200 5250) $PN 47
J 0
(-6190 5260);
DISPLAY 0.680851 (-6190 5260);
PAINT MONO (-6190 5260);
FORCEPROP 0 LASTPIN (-6200 3600) $PN 140
J 0
(-6190 3610);
DISPLAY 0.680851 (-6190 3610);
PAINT MONO (-6190 3610);
FORCEPROP 0 LASTPIN (-6200 5300) $PN 49
J 0
(-6190 5310);
DISPLAY 0.680851 (-6190 5310);
PAINT MONO (-6190 5310);
FORCEPROP 0 LASTPIN (-6200 3650) $PN 142
J 0
(-6190 3660);
DISPLAY 0.680851 (-6190 3660);
PAINT MONO (-6190 3660);
FORCEPROP 0 LASTPIN (-6200 5350) $PN 192
J 0
(-6190 5360);
DISPLAY 0.680851 (-6190 5360);
PAINT MONO (-6190 5360);
FORCEPROP 0 LASTPIN (-6200 3700) $PN 285
J 0
(-6190 3710);
DISPLAY 0.680851 (-6190 3710);
PAINT MONO (-6190 3710);
FORCEPROP 0 LASTPIN (-6200 5400) $PN 194
J 0
(-6190 5410);
DISPLAY 0.680851 (-6190 5410);
PAINT MONO (-6190 5410);
FORCEPROP 0 LASTPIN (-6200 3750) $PN 287
J 0
(-6190 3760);
DISPLAY 0.680851 (-6190 3760);
PAINT MONO (-6190 3760);
FORCEPROP 0 LASTPIN (-7400 2900) $PN 148
J 2
(-7410 2910);
DISPLAY 0.680851 (-7410 2910);
PAINT MONO (-7410 2910);
FORCEPROP 0 LASTPIN (-7400 2800) $PN 4
J 2
(-7410 2810);
DISPLAY 0.680851 (-7410 2810);
PAINT MONO (-7410 2810);
FORCEPROP 0 LASTPIN (-7400 2850) $PN 5
J 2
(-7410 2860);
DISPLAY 0.680851 (-7410 2860);
PAINT MONO (-7410 2860);
FORCEPROP 0 LASTPIN (-7400 2000) $PN 86
J 2
(-7410 2010);
DISPLAY 0.680851 (-7410 2010);
PAINT MONO (-7410 2010);
FORCEPROP 0 LASTPIN (-7400 1950) $PN 87
J 2
(-7410 1960);
DISPLAY 0.680851 (-7410 1960);
PAINT MONO (-7410 1960);
FORCEPROP 0 LASTPIN (-7400 4600) $PN 74
J 2
(-7410 4610);
DISPLAY 0.680851 (-7410 4610);
PAINT MONO (-7410 4610);
FORCEPROP 0 LASTPIN (-7400 4550) $PN 227
J 2
(-7410 4560);
DISPLAY 0.680851 (-7410 4560);
PAINT MONO (-7410 4560);
FORCEPROP 0 LASTPIN (-7400 2550) $PN 147
J 2
(-7410 2560);
DISPLAY 0.680851 (-7410 2560);
PAINT MONO (-7410 2560);
FORCEPROP 0 LASTPIN (-7400 3100) $PN 207
J 2
(-7410 3110);
DISPLAY 0.680851 (-7410 3110);
PAINT MONO (-7410 3110);
FORCEPROP 0 LASTPIN (-7400 2150) $PN 2
J 2
(-7410 2160);
DISPLAY 0.680851 (-7410 2160);
PAINT MONO (-7410 2160);
FORCEPROP 0 LASTPIN (-7400 2200) $PN 144
J 2
(-7410 2210);
DISPLAY 0.680851 (-7410 2210);
PAINT MONO (-7410 2210);
FORCEPROP 0 LASTPIN (-7400 2250) $PN 149
J 2
(-7410 2260);
DISPLAY 0.680851 (-7410 2260);
PAINT MONO (-7410 2260);
FORCEPROP 0 LASTPIN (-7400 2300) $PN 150
J 2
(-7410 2310);
DISPLAY 0.680851 (-7410 2310);
PAINT MONO (-7410 2310);
FORCEPROP 0 LASTPIN (-7400 2350) $PN 220
J 2
(-7410 2360);
DISPLAY 0.680851 (-7410 2360);
PAINT MONO (-7410 2360);
FORCEPROP 0 LASTPIN (-7400 2400) $PN 231
J 2
(-7410 2410);
DISPLAY 0.680851 (-7410 2410);
PAINT MONO (-7410 2410);
FORCEPROP 0 LASTPIN (-7400 2450) $PN 232
J 2
(-7410 2460);
DISPLAY 0.680851 (-7410 2460);
PAINT MONO (-7410 2460);
FORCEPROP 0 LASTPIN (-7400 2950) $PN 3
J 2
(-7410 2960);
DISPLAY 0.680851 (-7410 2960);
PAINT MONO (-7410 2960);
FORCEPROP 2 LAST VALUE SCONN288_DDR506112002KQ
J 0
(-7250 5775);
DISPLAY 0.489362 (-7250 5775);
PAINT SKYBLUE (-7250 5775);
FORCEPROP 2 LAST PART_TYPE SMLF
J 0
(-7250 5825);
DISPLAY 1.021277 (-7250 5825);
FORCEPROP 1 LAST MATERIAL IO
J 0
(-7250 5575);
DISPLAY 0.468085 (-7250 5575);
PAINT SKYBLUE (-7250 5575);
FORCEPROP 1 LAST CDS_LMAN_SYM_OUTLINE -450,1900,450,-1850
J 0
(-6800 3650);
DISPLAY 0.468085 (-6800 3650);
PAINT GREEN (-6800 3650);
DISPLAY INVISIBLE (-6800 3650);
FORCEPROP 1 LAST NEEDS_NO_SIZE TRUE
J 0
(-6800 3650);
DISPLAY 0.723404 (-6800 3650);
PAINT GREEN (-6800 3650);
DISPLAY INVISIBLE (-6800 3650);
FORCEPROP 2 LAST CDS_LIB pure_quanta
J 0
(-6800 3650);
DISPLAY INVISIBLE (-6800 3650);
FORCEPROP 1 LAST PATH I22
J 0
(-6800 3650);
DISPLAY 0.723404 (-6800 3650);
PAINT GREEN (-6800 3650);
DISPLAY INVISIBLE (-6800 3650);
FORCEPROP 1 LAST PART_NUMBER DFHST8FS479
J 0
(-7250 5650);
DISPLAY 0.468085 (-7250 5650);
PAINT SKYBLUE (-7250 5650);
DISPLAY INVISIBLE (-7250 5650);
FORCEADD TAP..1
(-3425 3375);
FORCEPROP 3 LASTPIN (-3475 3375) SIG_NAME M_H_CPU1_SB_DQS_DP<9>
J 0
(-3465 3385);
DISPLAY 0.659574 (-3465 3385);
PAINT MONO (-3465 3385);
DISPLAY INVISIBLE (-3465 3385);
FORCEPROP 1 LASTPIN (-3475 3375) BN 9
J 0
(-3487 3383);
DISPLAY 0.489362 (-3487 3383);
PAINT GREEN (-3487 3383);
FORCEPROP 2 LAST CDS_LIB mstr_standard
J 0
(-3425 3375);
DISPLAY 0.723404 (-3425 3375);
PAINT MONO (-3425 3375);
DISPLAY INVISIBLE (-3425 3375);
FORCEPROP 1 LAST BODY_TYPE PLUMBING
J 0
(-3425 3425);
DISPLAY 0.872340 (-3425 3425);
PAINT GREEN (-3425 3425);
DISPLAY INVISIBLE (-3425 3425);
FORCEPROP 1 LAST HDL_TAP TRUE
J 0
(-3100 3250);
DISPLAY 0.872340 (-3100 3250);
DISPLAY INVISIBLE (-3100 3250);
FORCEPROP 1 LAST PATH I220
J 0
(-3427 3375);
DISPLAY 0.872340 (-3427 3375);
PAINT GREEN (-3427 3375);
DISPLAY INVISIBLE (-3427 3375);
FORCEADD TAP..1
(-3425 3275);
FORCEPROP 3 LASTPIN (-3475 3275) SIG_NAME M_H_CPU1_SB_DQS_DP<8>
J 0
(-3465 3285);
DISPLAY 0.659574 (-3465 3285);
PAINT MONO (-3465 3285);
DISPLAY INVISIBLE (-3465 3285);
FORCEPROP 1 LASTPIN (-3475 3275) BN 8
J 0
(-3487 3283);
DISPLAY 0.489362 (-3487 3283);
PAINT GREEN (-3487 3283);
FORCEPROP 2 LAST CDS_LIB mstr_standard
J 0
(-3425 3275);
DISPLAY 0.723404 (-3425 3275);
PAINT MONO (-3425 3275);
DISPLAY INVISIBLE (-3425 3275);
FORCEPROP 1 LAST BODY_TYPE PLUMBING
J 0
(-3425 3325);
DISPLAY 0.872340 (-3425 3325);
PAINT GREEN (-3425 3325);
DISPLAY INVISIBLE (-3425 3325);
FORCEPROP 1 LAST HDL_TAP TRUE
J 0
(-3100 3150);
DISPLAY 0.872340 (-3100 3150);
DISPLAY INVISIBLE (-3100 3150);
FORCEPROP 1 LAST PATH I221
J 0
(-3427 3275);
DISPLAY 0.872340 (-3427 3275);
PAINT GREEN (-3427 3275);
DISPLAY INVISIBLE (-3427 3275);
FORCEADD TAP..1
(-3225 3125);
FORCEPROP 3 LASTPIN (-3275 3125) SIG_NAME M_H_CPU1_SB_DQS_DN<7>
J 0
(-3265 3135);
DISPLAY 0.659574 (-3265 3135);
PAINT MONO (-3265 3135);
DISPLAY INVISIBLE (-3265 3135);
FORCEPROP 1 LASTPIN (-3275 3125) BN 7
J 0
(-3287 3133);
DISPLAY 0.489362 (-3287 3133);
PAINT GREEN (-3287 3133);
FORCEPROP 2 LAST CDS_LIB mstr_standard
J 0
(-3225 3125);
DISPLAY 0.723404 (-3225 3125);
PAINT MONO (-3225 3125);
DISPLAY INVISIBLE (-3225 3125);
FORCEPROP 1 LAST BODY_TYPE PLUMBING
J 0
(-3225 3175);
DISPLAY 0.872340 (-3225 3175);
PAINT GREEN (-3225 3175);
DISPLAY INVISIBLE (-3225 3175);
FORCEPROP 1 LAST HDL_TAP TRUE
J 0
(-2900 3000);
DISPLAY 0.872340 (-2900 3000);
DISPLAY INVISIBLE (-2900 3000);
FORCEPROP 1 LAST PATH I222
J 0
(-3227 3125);
DISPLAY 0.872340 (-3227 3125);
PAINT GREEN (-3227 3125);
DISPLAY INVISIBLE (-3227 3125);
FORCEADD TAP..1
(-3225 3025);
FORCEPROP 3 LASTPIN (-3275 3025) SIG_NAME M_H_CPU1_SB_DQS_DN<6>
J 0
(-3265 3035);
DISPLAY 0.659574 (-3265 3035);
PAINT MONO (-3265 3035);
DISPLAY INVISIBLE (-3265 3035);
FORCEPROP 1 LASTPIN (-3275 3025) BN 6
J 0
(-3287 3033);
DISPLAY 0.489362 (-3287 3033);
PAINT GREEN (-3287 3033);
FORCEPROP 2 LAST CDS_LIB mstr_standard
J 0
(-3225 3025);
DISPLAY 0.723404 (-3225 3025);
PAINT MONO (-3225 3025);
DISPLAY INVISIBLE (-3225 3025);
FORCEPROP 1 LAST BODY_TYPE PLUMBING
J 0
(-3225 3075);
DISPLAY 0.872340 (-3225 3075);
PAINT GREEN (-3225 3075);
DISPLAY INVISIBLE (-3225 3075);
FORCEPROP 1 LAST HDL_TAP TRUE
J 0
(-2900 2900);
DISPLAY 0.872340 (-2900 2900);
DISPLAY INVISIBLE (-2900 2900);
FORCEPROP 1 LAST PATH I223
J 0
(-3227 3025);
DISPLAY 0.872340 (-3227 3025);
PAINT GREEN (-3227 3025);
DISPLAY INVISIBLE (-3227 3025);
FORCEADD TAP..1
(-3225 2925);
FORCEPROP 3 LASTPIN (-3275 2925) SIG_NAME M_H_CPU1_SB_DQS_DN<5>
J 0
(-3265 2935);
DISPLAY 0.659574 (-3265 2935);
PAINT MONO (-3265 2935);
DISPLAY INVISIBLE (-3265 2935);
FORCEPROP 1 LASTPIN (-3275 2925) BN 5
J 0
(-3287 2933);
DISPLAY 0.489362 (-3287 2933);
PAINT GREEN (-3287 2933);
FORCEPROP 2 LAST CDS_LIB mstr_standard
J 0
(-3225 2925);
DISPLAY 0.723404 (-3225 2925);
PAINT MONO (-3225 2925);
DISPLAY INVISIBLE (-3225 2925);
FORCEPROP 1 LAST BODY_TYPE PLUMBING
J 0
(-3225 2975);
DISPLAY 0.872340 (-3225 2975);
PAINT GREEN (-3225 2975);
DISPLAY INVISIBLE (-3225 2975);
FORCEPROP 1 LAST HDL_TAP TRUE
J 0
(-2900 2800);
DISPLAY 0.872340 (-2900 2800);
DISPLAY INVISIBLE (-2900 2800);
FORCEPROP 1 LAST PATH I224
J 0
(-3227 2925);
DISPLAY 0.872340 (-3227 2925);
PAINT GREEN (-3227 2925);
DISPLAY INVISIBLE (-3227 2925);
FORCEADD TAP..1
(-3225 2725);
FORCEPROP 3 LASTPIN (-3275 2725) SIG_NAME M_H_CPU1_SB_DQS_DN<3>
J 0
(-3265 2735);
DISPLAY 0.659574 (-3265 2735);
PAINT MONO (-3265 2735);
DISPLAY INVISIBLE (-3265 2735);
FORCEPROP 1 LASTPIN (-3275 2725) BN 3
J 0
(-3287 2733);
DISPLAY 0.489362 (-3287 2733);
PAINT GREEN (-3287 2733);
FORCEPROP 2 LAST CDS_LIB mstr_standard
J 0
(-3225 2725);
DISPLAY 0.723404 (-3225 2725);
PAINT MONO (-3225 2725);
DISPLAY INVISIBLE (-3225 2725);
FORCEPROP 1 LAST BODY_TYPE PLUMBING
J 0
(-3225 2775);
DISPLAY 0.872340 (-3225 2775);
PAINT GREEN (-3225 2775);
DISPLAY INVISIBLE (-3225 2775);
FORCEPROP 1 LAST HDL_TAP TRUE
J 0
(-2900 2600);
DISPLAY 0.872340 (-2900 2600);
DISPLAY INVISIBLE (-2900 2600);
FORCEPROP 1 LAST PATH I225
J 0
(-3227 2725);
DISPLAY 0.872340 (-3227 2725);
PAINT GREEN (-3227 2725);
DISPLAY INVISIBLE (-3227 2725);
FORCEADD TAP..1
(-3225 2825);
FORCEPROP 3 LASTPIN (-3275 2825) SIG_NAME M_H_CPU1_SB_DQS_DN<4>
J 0
(-3265 2835);
DISPLAY 0.659574 (-3265 2835);
PAINT MONO (-3265 2835);
DISPLAY INVISIBLE (-3265 2835);
FORCEPROP 1 LASTPIN (-3275 2825) BN 4
J 0
(-3287 2833);
DISPLAY 0.489362 (-3287 2833);
PAINT GREEN (-3287 2833);
FORCEPROP 2 LAST CDS_LIB mstr_standard
J 0
(-3225 2825);
DISPLAY 0.723404 (-3225 2825);
PAINT MONO (-3225 2825);
DISPLAY INVISIBLE (-3225 2825);
FORCEPROP 1 LAST BODY_TYPE PLUMBING
J 0
(-3225 2875);
DISPLAY 0.872340 (-3225 2875);
PAINT GREEN (-3225 2875);
DISPLAY INVISIBLE (-3225 2875);
FORCEPROP 1 LAST HDL_TAP TRUE
J 0
(-2900 2700);
DISPLAY 0.872340 (-2900 2700);
DISPLAY INVISIBLE (-2900 2700);
FORCEPROP 1 LAST PATH I226
J 0
(-3227 2825);
DISPLAY 0.872340 (-3227 2825);
PAINT GREEN (-3227 2825);
DISPLAY INVISIBLE (-3227 2825);
FORCEADD TAP..1
(-3225 2625);
FORCEPROP 3 LASTPIN (-3275 2625) SIG_NAME M_H_CPU1_SB_DQS_DN<2>
J 0
(-3265 2635);
DISPLAY 0.659574 (-3265 2635);
PAINT MONO (-3265 2635);
DISPLAY INVISIBLE (-3265 2635);
FORCEPROP 1 LASTPIN (-3275 2625) BN 2
J 0
(-3287 2633);
DISPLAY 0.489362 (-3287 2633);
PAINT GREEN (-3287 2633);
FORCEPROP 2 LAST CDS_LIB mstr_standard
J 0
(-3225 2625);
DISPLAY 0.723404 (-3225 2625);
PAINT MONO (-3225 2625);
DISPLAY INVISIBLE (-3225 2625);
FORCEPROP 1 LAST BODY_TYPE PLUMBING
J 0
(-3225 2675);
DISPLAY 0.872340 (-3225 2675);
PAINT GREEN (-3225 2675);
DISPLAY INVISIBLE (-3225 2675);
FORCEPROP 1 LAST HDL_TAP TRUE
J 0
(-2900 2500);
DISPLAY 0.872340 (-2900 2500);
DISPLAY INVISIBLE (-2900 2500);
FORCEPROP 1 LAST PATH I227
J 0
(-3227 2625);
DISPLAY 0.872340 (-3227 2625);
PAINT GREEN (-3227 2625);
DISPLAY INVISIBLE (-3227 2625);
FORCEADD TAP..1
(-3225 2525);
FORCEPROP 3 LASTPIN (-3275 2525) SIG_NAME M_H_CPU1_SB_DQS_DN<1>
J 0
(-3265 2535);
DISPLAY 0.659574 (-3265 2535);
PAINT MONO (-3265 2535);
DISPLAY INVISIBLE (-3265 2535);
FORCEPROP 1 LASTPIN (-3275 2525) BN 1
J 0
(-3287 2533);
DISPLAY 0.489362 (-3287 2533);
PAINT GREEN (-3287 2533);
FORCEPROP 2 LAST CDS_LIB mstr_standard
J 0
(-3225 2525);
DISPLAY 0.723404 (-3225 2525);
PAINT MONO (-3225 2525);
DISPLAY INVISIBLE (-3225 2525);
FORCEPROP 1 LAST BODY_TYPE PLUMBING
J 0
(-3225 2575);
DISPLAY 0.872340 (-3225 2575);
PAINT GREEN (-3225 2575);
DISPLAY INVISIBLE (-3225 2575);
FORCEPROP 1 LAST HDL_TAP TRUE
J 0
(-2900 2400);
DISPLAY 0.872340 (-2900 2400);
DISPLAY INVISIBLE (-2900 2400);
FORCEPROP 1 LAST PATH I228
J 0
(-3227 2525);
DISPLAY 0.872340 (-3227 2525);
PAINT GREEN (-3227 2525);
DISPLAY INVISIBLE (-3227 2525);
FORCEADD TAP..1
(-3225 2425);
FORCEPROP 3 LASTPIN (-3275 2425) SIG_NAME M_H_CPU1_SB_DQS_DN<0>
J 0
(-3265 2435);
DISPLAY 0.659574 (-3265 2435);
PAINT MONO (-3265 2435);
DISPLAY INVISIBLE (-3265 2435);
FORCEPROP 1 LASTPIN (-3275 2425) BN 0
J 0
(-3287 2433);
DISPLAY 0.489362 (-3287 2433);
PAINT GREEN (-3287 2433);
FORCEPROP 2 LAST CDS_LIB mstr_standard
J 0
(-3225 2425);
DISPLAY 0.723404 (-3225 2425);
PAINT MONO (-3225 2425);
DISPLAY INVISIBLE (-3225 2425);
FORCEPROP 1 LAST BODY_TYPE PLUMBING
J 0
(-3225 2475);
DISPLAY 0.872340 (-3225 2475);
PAINT GREEN (-3225 2475);
DISPLAY INVISIBLE (-3225 2475);
FORCEPROP 1 LAST HDL_TAP TRUE
J 0
(-2900 2300);
DISPLAY 0.872340 (-2900 2300);
DISPLAY INVISIBLE (-2900 2300);
FORCEPROP 1 LAST PATH I229
J 0
(-3227 2425);
DISPLAY 0.872340 (-3227 2425);
PAINT GREEN (-3227 2425);
DISPLAY INVISIBLE (-3227 2425);
FORCEADD TAP..1
R 2
(-7650 3300);
FORCEPROP 3 LASTPIN (-7600 3300) SIG_NAME M_H_CPU1_SB_CB<2>
J 0
(-7590 3310);
DISPLAY 0.659574 (-7590 3310);
PAINT MONO (-7590 3310);
DISPLAY INVISIBLE (-7590 3310);
FORCEPROP 1 LASTPIN (-7600 3300) BN 2
J 2
(-7588 3308);
DISPLAY 0.489362 (-7588 3308);
PAINT GREEN (-7588 3308);
FORCEPROP 2 LAST CDS_LIB mstr_standard
J 0
(-7650 3300);
DISPLAY 0.723404 (-7650 3300);
PAINT MONO (-7650 3300);
DISPLAY INVISIBLE (-7650 3300);
FORCEPROP 1 LAST BODY_TYPE PLUMBING
J 2
(-7650 3350);
DISPLAY 0.872340 (-7650 3350);
PAINT GREEN (-7650 3350);
DISPLAY INVISIBLE (-7650 3350);
FORCEPROP 1 LAST HDL_TAP TRUE
J 2
(-7975 3175);
DISPLAY 0.872340 (-7975 3175);
DISPLAY INVISIBLE (-7975 3175);
FORCEPROP 1 LAST PATH I23
J 2
(-7648 3300);
DISPLAY 0.872340 (-7648 3300);
PAINT GREEN (-7648 3300);
DISPLAY INVISIBLE (-7648 3300);
FORCEADD TAP..1
(-3425 3175);
FORCEPROP 3 LASTPIN (-3475 3175) SIG_NAME M_H_CPU1_SB_DQS_DP<7>
J 0
(-3465 3185);
DISPLAY 0.659574 (-3465 3185);
PAINT MONO (-3465 3185);
DISPLAY INVISIBLE (-3465 3185);
FORCEPROP 1 LASTPIN (-3475 3175) BN 7
J 0
(-3487 3183);
DISPLAY 0.489362 (-3487 3183);
PAINT GREEN (-3487 3183);
FORCEPROP 2 LAST CDS_LIB mstr_standard
J 0
(-3425 3175);
DISPLAY 0.723404 (-3425 3175);
PAINT MONO (-3425 3175);
DISPLAY INVISIBLE (-3425 3175);
FORCEPROP 1 LAST BODY_TYPE PLUMBING
J 0
(-3425 3225);
DISPLAY 0.872340 (-3425 3225);
PAINT GREEN (-3425 3225);
DISPLAY INVISIBLE (-3425 3225);
FORCEPROP 1 LAST HDL_TAP TRUE
J 0
(-3100 3050);
DISPLAY 0.872340 (-3100 3050);
DISPLAY INVISIBLE (-3100 3050);
FORCEPROP 1 LAST PATH I230
J 0
(-3427 3175);
DISPLAY 0.872340 (-3427 3175);
PAINT GREEN (-3427 3175);
DISPLAY INVISIBLE (-3427 3175);
FORCEADD TAP..1
(-3425 3075);
FORCEPROP 3 LASTPIN (-3475 3075) SIG_NAME M_H_CPU1_SB_DQS_DP<6>
J 0
(-3465 3085);
DISPLAY 0.659574 (-3465 3085);
PAINT MONO (-3465 3085);
DISPLAY INVISIBLE (-3465 3085);
FORCEPROP 1 LASTPIN (-3475 3075) BN 6
J 0
(-3487 3083);
DISPLAY 0.489362 (-3487 3083);
PAINT GREEN (-3487 3083);
FORCEPROP 2 LAST CDS_LIB mstr_standard
J 0
(-3425 3075);
DISPLAY 0.723404 (-3425 3075);
PAINT MONO (-3425 3075);
DISPLAY INVISIBLE (-3425 3075);
FORCEPROP 1 LAST BODY_TYPE PLUMBING
J 0
(-3425 3125);
DISPLAY 0.872340 (-3425 3125);
PAINT GREEN (-3425 3125);
DISPLAY INVISIBLE (-3425 3125);
FORCEPROP 1 LAST HDL_TAP TRUE
J 0
(-3100 2950);
DISPLAY 0.872340 (-3100 2950);
DISPLAY INVISIBLE (-3100 2950);
FORCEPROP 1 LAST PATH I231
J 0
(-3427 3075);
DISPLAY 0.872340 (-3427 3075);
PAINT GREEN (-3427 3075);
DISPLAY INVISIBLE (-3427 3075);
FORCEADD TAP..1
(-3425 2975);
FORCEPROP 3 LASTPIN (-3475 2975) SIG_NAME M_H_CPU1_SB_DQS_DP<5>
J 0
(-3465 2985);
DISPLAY 0.659574 (-3465 2985);
PAINT MONO (-3465 2985);
DISPLAY INVISIBLE (-3465 2985);
FORCEPROP 1 LASTPIN (-3475 2975) BN 5
J 0
(-3487 2983);
DISPLAY 0.489362 (-3487 2983);
PAINT GREEN (-3487 2983);
FORCEPROP 2 LAST CDS_LIB mstr_standard
J 0
(-3425 2975);
DISPLAY 0.723404 (-3425 2975);
PAINT MONO (-3425 2975);
DISPLAY INVISIBLE (-3425 2975);
FORCEPROP 1 LAST BODY_TYPE PLUMBING
J 0
(-3425 3025);
DISPLAY 0.872340 (-3425 3025);
PAINT GREEN (-3425 3025);
DISPLAY INVISIBLE (-3425 3025);
FORCEPROP 1 LAST HDL_TAP TRUE
J 0
(-3100 2850);
DISPLAY 0.872340 (-3100 2850);
DISPLAY INVISIBLE (-3100 2850);
FORCEPROP 1 LAST PATH I232
J 0
(-3427 2975);
DISPLAY 0.872340 (-3427 2975);
PAINT GREEN (-3427 2975);
DISPLAY INVISIBLE (-3427 2975);
FORCEADD TAP..1
(-3425 2875);
FORCEPROP 3 LASTPIN (-3475 2875) SIG_NAME M_H_CPU1_SB_DQS_DP<4>
J 0
(-3465 2885);
DISPLAY 0.659574 (-3465 2885);
PAINT MONO (-3465 2885);
DISPLAY INVISIBLE (-3465 2885);
FORCEPROP 1 LASTPIN (-3475 2875) BN 4
J 0
(-3487 2883);
DISPLAY 0.489362 (-3487 2883);
PAINT GREEN (-3487 2883);
FORCEPROP 2 LAST CDS_LIB mstr_standard
J 0
(-3425 2875);
DISPLAY 0.723404 (-3425 2875);
PAINT MONO (-3425 2875);
DISPLAY INVISIBLE (-3425 2875);
FORCEPROP 1 LAST BODY_TYPE PLUMBING
J 0
(-3425 2925);
DISPLAY 0.872340 (-3425 2925);
PAINT GREEN (-3425 2925);
DISPLAY INVISIBLE (-3425 2925);
FORCEPROP 1 LAST HDL_TAP TRUE
J 0
(-3100 2750);
DISPLAY 0.872340 (-3100 2750);
DISPLAY INVISIBLE (-3100 2750);
FORCEPROP 1 LAST PATH I233
J 0
(-3427 2875);
DISPLAY 0.872340 (-3427 2875);
PAINT GREEN (-3427 2875);
DISPLAY INVISIBLE (-3427 2875);
FORCEADD TAP..1
(-3425 2775);
FORCEPROP 3 LASTPIN (-3475 2775) SIG_NAME M_H_CPU1_SB_DQS_DP<3>
J 0
(-3465 2785);
DISPLAY 0.659574 (-3465 2785);
PAINT MONO (-3465 2785);
DISPLAY INVISIBLE (-3465 2785);
FORCEPROP 1 LASTPIN (-3475 2775) BN 3
J 0
(-3487 2783);
DISPLAY 0.489362 (-3487 2783);
PAINT GREEN (-3487 2783);
FORCEPROP 2 LAST CDS_LIB mstr_standard
J 0
(-3425 2775);
DISPLAY 0.723404 (-3425 2775);
PAINT MONO (-3425 2775);
DISPLAY INVISIBLE (-3425 2775);
FORCEPROP 1 LAST BODY_TYPE PLUMBING
J 0
(-3425 2825);
DISPLAY 0.872340 (-3425 2825);
PAINT GREEN (-3425 2825);
DISPLAY INVISIBLE (-3425 2825);
FORCEPROP 1 LAST HDL_TAP TRUE
J 0
(-3100 2650);
DISPLAY 0.872340 (-3100 2650);
DISPLAY INVISIBLE (-3100 2650);
FORCEPROP 1 LAST PATH I234
J 0
(-3427 2775);
DISPLAY 0.872340 (-3427 2775);
PAINT GREEN (-3427 2775);
DISPLAY INVISIBLE (-3427 2775);
FORCEADD TAP..1
(-3425 2675);
FORCEPROP 3 LASTPIN (-3475 2675) SIG_NAME M_H_CPU1_SB_DQS_DP<2>
J 0
(-3465 2685);
DISPLAY 0.659574 (-3465 2685);
PAINT MONO (-3465 2685);
DISPLAY INVISIBLE (-3465 2685);
FORCEPROP 1 LASTPIN (-3475 2675) BN 2
J 0
(-3487 2683);
DISPLAY 0.489362 (-3487 2683);
PAINT GREEN (-3487 2683);
FORCEPROP 2 LAST CDS_LIB mstr_standard
J 0
(-3425 2675);
DISPLAY 0.723404 (-3425 2675);
PAINT MONO (-3425 2675);
DISPLAY INVISIBLE (-3425 2675);
FORCEPROP 1 LAST BODY_TYPE PLUMBING
J 0
(-3425 2725);
DISPLAY 0.872340 (-3425 2725);
PAINT GREEN (-3425 2725);
DISPLAY INVISIBLE (-3425 2725);
FORCEPROP 1 LAST HDL_TAP TRUE
J 0
(-3100 2550);
DISPLAY 0.872340 (-3100 2550);
DISPLAY INVISIBLE (-3100 2550);
FORCEPROP 1 LAST PATH I235
J 0
(-3427 2675);
DISPLAY 0.872340 (-3427 2675);
PAINT GREEN (-3427 2675);
DISPLAY INVISIBLE (-3427 2675);
FORCEADD TAP..1
(-3425 2575);
FORCEPROP 3 LASTPIN (-3475 2575) SIG_NAME M_H_CPU1_SB_DQS_DP<1>
J 0
(-3465 2585);
DISPLAY 0.659574 (-3465 2585);
PAINT MONO (-3465 2585);
DISPLAY INVISIBLE (-3465 2585);
FORCEPROP 1 LASTPIN (-3475 2575) BN 1
J 0
(-3487 2583);
DISPLAY 0.489362 (-3487 2583);
PAINT GREEN (-3487 2583);
FORCEPROP 2 LAST CDS_LIB mstr_standard
J 0
(-3425 2575);
DISPLAY 0.723404 (-3425 2575);
PAINT MONO (-3425 2575);
DISPLAY INVISIBLE (-3425 2575);
FORCEPROP 1 LAST BODY_TYPE PLUMBING
J 0
(-3425 2625);
DISPLAY 0.872340 (-3425 2625);
PAINT GREEN (-3425 2625);
DISPLAY INVISIBLE (-3425 2625);
FORCEPROP 1 LAST HDL_TAP TRUE
J 0
(-3100 2450);
DISPLAY 0.872340 (-3100 2450);
DISPLAY INVISIBLE (-3100 2450);
FORCEPROP 1 LAST PATH I236
J 0
(-3427 2575);
DISPLAY 0.872340 (-3427 2575);
PAINT GREEN (-3427 2575);
DISPLAY INVISIBLE (-3427 2575);
FORCEADD TAP..1
(-3425 2475);
FORCEPROP 3 LASTPIN (-3475 2475) SIG_NAME M_H_CPU1_SB_DQS_DP<0>
J 0
(-3465 2485);
DISPLAY 0.659574 (-3465 2485);
PAINT MONO (-3465 2485);
DISPLAY INVISIBLE (-3465 2485);
FORCEPROP 1 LASTPIN (-3475 2475) BN 0
J 0
(-3487 2483);
DISPLAY 0.489362 (-3487 2483);
PAINT GREEN (-3487 2483);
FORCEPROP 2 LAST CDS_LIB mstr_standard
J 0
(-3425 2475);
DISPLAY 0.723404 (-3425 2475);
PAINT MONO (-3425 2475);
DISPLAY INVISIBLE (-3425 2475);
FORCEPROP 1 LAST BODY_TYPE PLUMBING
J 0
(-3425 2525);
DISPLAY 0.872340 (-3425 2525);
PAINT GREEN (-3425 2525);
DISPLAY INVISIBLE (-3425 2525);
FORCEPROP 1 LAST HDL_TAP TRUE
J 0
(-3100 2350);
DISPLAY 0.872340 (-3100 2350);
DISPLAY INVISIBLE (-3100 2350);
FORCEPROP 1 LAST PATH I237
J 0
(-3427 2475);
DISPLAY 0.872340 (-3427 2475);
PAINT GREEN (-3427 2475);
DISPLAY INVISIBLE (-3427 2475);
FORCEADD SCONN288_DDR506112002KQ..2
(-4375 3425);
FORCEPROP 1 LAST LOCATION J27
J 0
(-4975 4750);
DISPLAY 0.468085 (-4975 4750);
PAINT SKYBLUE (-4975 4750);
FORCEPROP 0 LAST $SEC 2
J 0
(-4825 4900);
DISPLAY 0.680851 (-4825 4900);
PAINT MONO (-4825 4900);
DISPLAY INVISIBLE (-4825 4900);
FORCEPROP 0 LAST CDS_SEC 2
J 0
(-4825 4900);
DISPLAY 1.021277 (-4825 4900);
DISPLAY INVISIBLE (-4825 4900);
FORCEPROP 0 LASTPIN (-3625 3475) $PN 12
J 0
(-3615 3485);
DISPLAY 0.680851 (-3615 3485);
PAINT MONO (-3615 3485);
FORCEPROP 0 LASTPIN (-3625 3525) $PN 11
J 0
(-3615 3535);
DISPLAY 0.680851 (-3615 3535);
PAINT MONO (-3615 3535);
FORCEPROP 0 LASTPIN (-3625 2425) $PN 105
J 0
(-3615 2435);
DISPLAY 0.680851 (-3615 2435);
PAINT MONO (-3615 2435);
FORCEPROP 0 LASTPIN (-3625 2475) $PN 104
J 0
(-3615 2485);
DISPLAY 0.680851 (-3615 2485);
PAINT MONO (-3615 2485);
FORCEPROP 0 LASTPIN (-3625 3575) $PN 23
J 0
(-3615 3585);
DISPLAY 0.680851 (-3615 3585);
PAINT MONO (-3615 3585);
FORCEPROP 0 LASTPIN (-3625 3625) $PN 22
J 0
(-3615 3635);
DISPLAY 0.680851 (-3615 3635);
PAINT MONO (-3615 3635);
FORCEPROP 0 LASTPIN (-3625 2525) $PN 116
J 0
(-3615 2535);
DISPLAY 0.680851 (-3615 2535);
PAINT MONO (-3615 2535);
FORCEPROP 0 LASTPIN (-3625 2575) $PN 115
J 0
(-3615 2585);
DISPLAY 0.680851 (-3615 2585);
PAINT MONO (-3615 2585);
FORCEPROP 0 LASTPIN (-3625 3675) $PN 34
J 0
(-3615 3685);
DISPLAY 0.680851 (-3615 3685);
PAINT MONO (-3615 3685);
FORCEPROP 0 LASTPIN (-3625 3725) $PN 33
J 0
(-3615 3735);
DISPLAY 0.680851 (-3615 3735);
PAINT MONO (-3615 3735);
FORCEPROP 0 LASTPIN (-3625 2625) $PN 127
J 0
(-3615 2635);
DISPLAY 0.680851 (-3615 2635);
PAINT MONO (-3615 2635);
FORCEPROP 0 LASTPIN (-3625 2675) $PN 126
J 0
(-3615 2685);
DISPLAY 0.680851 (-3615 2685);
PAINT MONO (-3615 2685);
FORCEPROP 0 LASTPIN (-3625 3775) $PN 45
J 0
(-3615 3785);
DISPLAY 0.680851 (-3615 3785);
PAINT MONO (-3615 3785);
FORCEPROP 0 LASTPIN (-3625 3825) $PN 44
J 0
(-3615 3835);
DISPLAY 0.680851 (-3615 3835);
PAINT MONO (-3615 3835);
FORCEPROP 0 LASTPIN (-3625 2725) $PN 138
J 0
(-3615 2735);
DISPLAY 0.680851 (-3615 2735);
PAINT MONO (-3615 2735);
FORCEPROP 0 LASTPIN (-3625 2775) $PN 137
J 0
(-3615 2785);
DISPLAY 0.680851 (-3615 2785);
PAINT MONO (-3615 2785);
FORCEPROP 0 LASTPIN (-3625 3875) $PN 56
J 0
(-3615 3885);
DISPLAY 0.680851 (-3615 3885);
PAINT MONO (-3615 3885);
FORCEPROP 0 LASTPIN (-3625 3925) $PN 55
J 0
(-3615 3935);
DISPLAY 0.680851 (-3615 3935);
PAINT MONO (-3615 3935);
FORCEPROP 0 LASTPIN (-3625 2825) $PN 238
J 0
(-3615 2835);
DISPLAY 0.680851 (-3615 2835);
PAINT MONO (-3615 2835);
FORCEPROP 0 LASTPIN (-3625 2875) $PN 239
J 0
(-3615 2885);
DISPLAY 0.680851 (-3615 2885);
PAINT MONO (-3615 2885);
FORCEPROP 0 LASTPIN (-3625 3975) $PN 156
J 0
(-3615 3985);
DISPLAY 0.680851 (-3615 3985);
PAINT MONO (-3615 3985);
FORCEPROP 0 LASTPIN (-3625 4025) $PN 157
J 0
(-3615 4035);
DISPLAY 0.680851 (-3615 4035);
PAINT MONO (-3615 4035);
FORCEPROP 0 LASTPIN (-3625 2925) $PN 249
J 0
(-3615 2935);
DISPLAY 0.680851 (-3615 2935);
PAINT MONO (-3615 2935);
FORCEPROP 0 LASTPIN (-3625 2975) $PN 250
J 0
(-3615 2985);
DISPLAY 0.680851 (-3615 2985);
PAINT MONO (-3615 2985);
FORCEPROP 0 LASTPIN (-3625 4075) $PN 167
J 0
(-3615 4085);
DISPLAY 0.680851 (-3615 4085);
PAINT MONO (-3615 4085);
FORCEPROP 0 LASTPIN (-3625 4125) $PN 168
J 0
(-3615 4135);
DISPLAY 0.680851 (-3615 4135);
PAINT MONO (-3615 4135);
FORCEPROP 0 LASTPIN (-3625 3025) $PN 260
J 0
(-3615 3035);
DISPLAY 0.680851 (-3615 3035);
PAINT MONO (-3615 3035);
FORCEPROP 0 LASTPIN (-3625 3075) $PN 261
J 0
(-3615 3085);
DISPLAY 0.680851 (-3615 3085);
PAINT MONO (-3615 3085);
FORCEPROP 0 LASTPIN (-3625 4175) $PN 178
J 0
(-3615 4185);
DISPLAY 0.680851 (-3615 4185);
PAINT MONO (-3615 4185);
FORCEPROP 0 LASTPIN (-3625 4225) $PN 179
J 0
(-3615 4235);
DISPLAY 0.680851 (-3615 4235);
PAINT MONO (-3615 4235);
FORCEPROP 0 LASTPIN (-3625 3125) $PN 271
J 0
(-3615 3135);
DISPLAY 0.680851 (-3615 3135);
PAINT MONO (-3615 3135);
FORCEPROP 0 LASTPIN (-3625 3175) $PN 272
J 0
(-3615 3185);
DISPLAY 0.680851 (-3615 3185);
PAINT MONO (-3615 3185);
FORCEPROP 0 LASTPIN (-3625 4275) $PN 189
J 0
(-3615 4285);
DISPLAY 0.680851 (-3615 4285);
PAINT MONO (-3615 4285);
FORCEPROP 0 LASTPIN (-3625 4325) $PN 190
J 0
(-3615 4335);
DISPLAY 0.680851 (-3615 4335);
PAINT MONO (-3615 4335);
FORCEPROP 0 LASTPIN (-3625 3225) $PN 282
J 0
(-3615 3235);
DISPLAY 0.680851 (-3615 3235);
PAINT MONO (-3615 3235);
FORCEPROP 0 LASTPIN (-3625 3275) $PN 283
J 0
(-3615 3285);
DISPLAY 0.680851 (-3615 3285);
PAINT MONO (-3615 3285);
FORCEPROP 0 LASTPIN (-3625 4375) $PN 200
J 0
(-3615 4385);
DISPLAY 0.680851 (-3615 4385);
PAINT MONO (-3615 4385);
FORCEPROP 0 LASTPIN (-3625 4425) $PN 201
J 0
(-3615 4435);
DISPLAY 0.680851 (-3615 4435);
PAINT MONO (-3615 4435);
FORCEPROP 0 LASTPIN (-3625 3325) $PN 94
J 0
(-3615 3335);
DISPLAY 0.680851 (-3615 3335);
PAINT MONO (-3615 3335);
FORCEPROP 0 LASTPIN (-3625 3375) $PN 93
J 0
(-3615 3385);
DISPLAY 0.680851 (-3615 3385);
PAINT MONO (-3615 3385);
FORCEPROP 2 LAST PART_TYPE SMLF
J 0
(-4825 4850);
DISPLAY 1.021277 (-4825 4850);
FORCEPROP 1 LAST MATERIAL IO
J 0
(-4975 4600);
DISPLAY 0.468085 (-4975 4600);
PAINT SKYBLUE (-4975 4600);
FORCEPROP 2 LAST VALUE SCONN288_DDR506112002KQ
J 0
(-4825 4800);
DISPLAY 0.489362 (-4825 4800);
PAINT SKYBLUE (-4825 4800);
FORCEPROP 1 LAST CDS_LMAN_SYM_OUTLINE -600,1150,600,-1150
J 0
(-4375 3425);
DISPLAY 0.468085 (-4375 3425);
PAINT GREEN (-4375 3425);
DISPLAY INVISIBLE (-4375 3425);
FORCEPROP 1 LAST NEEDS_NO_SIZE TRUE
J 0
(-4375 3425);
DISPLAY 0.723404 (-4375 3425);
PAINT GREEN (-4375 3425);
DISPLAY INVISIBLE (-4375 3425);
FORCEPROP 2 LAST CDS_LIB pure_quanta
J 0
(-4375 3425);
DISPLAY INVISIBLE (-4375 3425);
FORCEPROP 1 LAST PATH I238
J 0
(-4375 3425);
DISPLAY 0.723404 (-4375 3425);
PAINT GREEN (-4375 3425);
DISPLAY INVISIBLE (-4375 3425);
FORCEPROP 1 LAST PART_NUMBER DFHST8FS479
J 0
(-4975 4675);
DISPLAY 0.468085 (-4975 4675);
PAINT SKYBLUE (-4975 4675);
DISPLAY INVISIBLE (-4975 4675);
FORCEADD GND..1
(-2825 5525);
FORCEPROP 3 LASTPIN (-2825 5575) SIG_NAME GND\g
J 0
(-2815 5585);
DISPLAY 0.659574 (-2815 5585);
PAINT MONO (-2815 5585);
DISPLAY INVISIBLE (-2815 5585);
FORCEPROP 2 LAST CDS_LIB pure_quanta_power
J 0
(-2825 5525);
DISPLAY INVISIBLE (-2825 5525);
FORCEPROP 2 LAST BOM_COST MEM
J 0
(-2800 5650);
DISPLAY 0.659574 (-2800 5650);
DISPLAY INVISIBLE (-2800 5650);
FORCEPROP 1 LAST SIZE 1B
J 0
(-2750 5475);
DISPLAY 0.723404 (-2750 5475);
PAINT GREEN (-2750 5475);
DISPLAY INVISIBLE (-2750 5475);
FORCEPROP 2 LAST ROOM MEM_EFGH_DECOUPLING_CAPS
J 0
(-2800 5600);
DISPLAY 0.659574 (-2800 5600);
PAINT RED (-2800 5600);
DISPLAY INVISIBLE (-2800 5600);
FORCEPROP 1 LAST HDL_POWER GND
J 0
(-2825 5675);
DISPLAY 0.723404 (-2825 5675);
PAINT GREEN (-2825 5675);
DISPLAY INVISIBLE (-2825 5675);
FORCEPROP 1 LAST PATH I239
J 0
(-2750 5525);
DISPLAY 0.872340 (-2750 5525);
PAINT AQUA (-2750 5525);
DISPLAY INVISIBLE (-2750 5525);
FORCEADD TAP..1
R 2
(-7650 3350);
FORCEPROP 3 LASTPIN (-7600 3350) SIG_NAME M_H_CPU1_SB_CB<3>
J 0
(-7590 3360);
DISPLAY 0.659574 (-7590 3360);
PAINT MONO (-7590 3360);
DISPLAY INVISIBLE (-7590 3360);
FORCEPROP 1 LASTPIN (-7600 3350) BN 3
J 2
(-7588 3358);
DISPLAY 0.489362 (-7588 3358);
PAINT GREEN (-7588 3358);
FORCEPROP 2 LAST CDS_LIB mstr_standard
J 0
(-7650 3350);
DISPLAY 0.723404 (-7650 3350);
PAINT MONO (-7650 3350);
DISPLAY INVISIBLE (-7650 3350);
FORCEPROP 1 LAST BODY_TYPE PLUMBING
J 2
(-7650 3400);
DISPLAY 0.872340 (-7650 3400);
PAINT GREEN (-7650 3400);
DISPLAY INVISIBLE (-7650 3400);
FORCEPROP 1 LAST HDL_TAP TRUE
J 2
(-7975 3225);
DISPLAY 0.872340 (-7975 3225);
DISPLAY INVISIBLE (-7975 3225);
FORCEPROP 1 LAST PATH I24
J 2
(-7648 3350);
DISPLAY 0.872340 (-7648 3350);
PAINT GREEN (-7648 3350);
DISPLAY INVISIBLE (-7648 3350);
FORCEADD Q_CAP..1
R 2
(-2825 5875);
FORCEPROP 1 LAST LOCATION C532
J 2
(-2875 5975);
DISPLAY 0.489362 (-2875 5975);
PAINT SKYBLUE (-2875 5975);
FORCEPROP 0 LAST $SEC 1
J 0
(-2875 6025);
DISPLAY 0.680851 (-2875 6025);
PAINT MONO (-2875 6025);
DISPLAY INVISIBLE (-2875 6025);
FORCEPROP 0 LAST CDS_SEC 1
J 0
(-2875 6025);
DISPLAY 0.680851 (-2875 6025);
DISPLAY INVISIBLE (-2875 6025);
FORCEPROP 1 LASTPIN (-2825 5975) $PN 1
J 2
(-2835 5955);
DISPLAY 0.489362 (-2835 5955);
PAINT MONO (-2835 5955);
FORCEPROP 1 LASTPIN (-2825 5775) $PN 2
J 2
(-2835 5755);
DISPLAY 0.489362 (-2835 5755);
PAINT MONO (-2835 5755);
FORCEPROP 1 LAST PACK_TYPE C0805
J 2
(-2875 5675);
DISPLAY 0.489362 (-2875 5675);
PAINT SKYBLUE (-2875 5675);
FORCEPROP 1 LAST VOLTAGE 25V
J 2
(-2875 5875);
DISPLAY 0.489362 (-2875 5875);
PAINT SKYBLUE (-2875 5875);
FORCEPROP 1 LAST VALUE 10UF
J 2
(-2875 5925);
DISPLAY 0.489362 (-2875 5925);
PAINT SKYBLUE (-2875 5925);
FORCEPROP 1 LAST TOLERANCE 10%
J 2
(-2875 5825);
DISPLAY 0.489362 (-2875 5825);
PAINT SKYBLUE (-2875 5825);
FORCEPROP 1 LAST MATERIAL X6S
J 2
(-2875 5775);
DISPLAY 0.489362 (-2875 5775);
PAINT SKYBLUE (-2875 5775);
FORCEPROP 2 LAST CDS_LIB pure_quanta
J 0
(-2825 5875);
DISPLAY INVISIBLE (-2825 5875);
FORCEPROP 0 LAST BOM_COST MEM
J 2
(-2880 6020);
DISPLAY 0.595745 (-2880 6020);
PAINT MONO (-2880 6020);
DISPLAY INVISIBLE (-2880 6020);
FORCEPROP 2 LAST ROOM 
J 2
(-2880 6020);
DISPLAY 0.595745 (-2880 6020);
PAINT RED (-2880 6020);
DISPLAY INVISIBLE (-2880 6020);
FORCEPROP 1 LAST PATH I240
J 2
(-2875 6025);
DISPLAY 0.978723 (-2875 6025);
PAINT WHITE (-2875 6025);
DISPLAY INVISIBLE (-2875 6025);
FORCEPROP 1 LAST PART_NUMBER CH6104KEA00
J 2
(-2875 5725);
DISPLAY 0.489362 (-2875 5725);
PAINT SKYBLUE (-2875 5725);
DISPLAY INVISIBLE (-2875 5725);
FORCEADD Q_CAP..1
R 2
(-2250 5875);
FORCEPROP 1 LAST LOCATION C533
J 2
(-2300 5975);
DISPLAY 0.489362 (-2300 5975);
PAINT SKYBLUE (-2300 5975);
FORCEPROP 0 LAST $SEC 1
J 0
(-2300 6025);
DISPLAY 0.680851 (-2300 6025);
PAINT MONO (-2300 6025);
DISPLAY INVISIBLE (-2300 6025);
FORCEPROP 0 LAST CDS_SEC 1
J 0
(-2300 6025);
DISPLAY 0.680851 (-2300 6025);
DISPLAY INVISIBLE (-2300 6025);
FORCEPROP 1 LASTPIN (-2250 5975) $PN 1
J 2
(-2260 5955);
DISPLAY 0.489362 (-2260 5955);
PAINT MONO (-2260 5955);
FORCEPROP 1 LASTPIN (-2250 5775) $PN 2
J 2
(-2260 5755);
DISPLAY 0.489362 (-2260 5755);
PAINT MONO (-2260 5755);
FORCEPROP 1 LAST PACK_TYPE C0805
J 2
(-2300 5675);
DISPLAY 0.489362 (-2300 5675);
PAINT SKYBLUE (-2300 5675);
FORCEPROP 1 LAST VOLTAGE 25V
J 2
(-2300 5875);
DISPLAY 0.489362 (-2300 5875);
PAINT SKYBLUE (-2300 5875);
FORCEPROP 1 LAST VALUE 10UF
J 2
(-2300 5925);
DISPLAY 0.489362 (-2300 5925);
PAINT SKYBLUE (-2300 5925);
FORCEPROP 1 LAST TOLERANCE 10%
J 2
(-2300 5825);
DISPLAY 0.489362 (-2300 5825);
PAINT SKYBLUE (-2300 5825);
FORCEPROP 1 LAST MATERIAL X6S
J 2
(-2300 5775);
DISPLAY 0.489362 (-2300 5775);
PAINT SKYBLUE (-2300 5775);
FORCEPROP 2 LAST CDS_LIB pure_quanta
J 0
(-2250 5875);
DISPLAY INVISIBLE (-2250 5875);
FORCEPROP 0 LAST BOM_COST MEM
J 2
(-2305 6020);
DISPLAY 0.595745 (-2305 6020);
PAINT MONO (-2305 6020);
DISPLAY INVISIBLE (-2305 6020);
FORCEPROP 2 LAST ROOM 
J 2
(-2305 6020);
DISPLAY 0.595745 (-2305 6020);
PAINT RED (-2305 6020);
DISPLAY INVISIBLE (-2305 6020);
FORCEPROP 1 LAST PATH I241
J 2
(-2300 6025);
DISPLAY 0.978723 (-2300 6025);
PAINT WHITE (-2300 6025);
DISPLAY INVISIBLE (-2300 6025);
FORCEPROP 1 LAST PART_NUMBER CH6104KEA00
J 2
(-2300 5725);
DISPLAY 0.489362 (-2300 5725);
PAINT SKYBLUE (-2300 5725);
DISPLAY INVISIBLE (-2300 5725);
FORCEADD UNIVERSAL_POWER..1
(-2825 6200);
FORCEPROP 3 LASTPIN (-2825 6150) SIG_NAME P12V_MEM_CPU1\g
J 0
(-2815 6160);
DISPLAY 0.659574 (-2815 6160);
PAINT MONO (-2815 6160);
DISPLAY INVISIBLE (-2815 6160);
FORCEPROP 1 LAST HDL_POWER P12V_MEM_CPU1
J 1
(-2825 6250);
DISPLAY 0.489362 (-2825 6250);
PAINT GREEN (-2825 6250);
FORCEPROP 2 LAST CDS_LIB pure_quanta_power
J 0
(-2825 6200);
DISPLAY INVISIBLE (-2825 6200);
FORCEPROP 1 LAST PATH I242
J 0
(-2775 6225);
DISPLAY 0.872340 (-2775 6225);
PAINT AQUA (-2775 6225);
DISPLAY INVISIBLE (-2775 6225);
FORCEADD OFFPAGE..1
(-8325 2625);
FORCEPROP 2 LAST $XR5 109 
J 0
(-9177 2625);
DISPLAY 0.638298 (-9177 2625);
PAINT MONO (-9177 2625);
FORCEPROP 2 LAST $XR4 108 
J 0
(-9057 2625);
DISPLAY 0.638298 (-9057 2625);
PAINT MONO (-9057 2625);
FORCEPROP 2 LAST $XR3 107 
J 0
(-8937 2625);
DISPLAY 0.638298 (-8937 2625);
PAINT MONO (-8937 2625);
FORCEPROP 2 LAST $XR2 106 
J 0
(-8817 2625);
DISPLAY 0.638298 (-8817 2625);
PAINT MONO (-8817 2625);
FORCEPROP 2 LAST $XR1 104 
J 0
(-8697 2625);
DISPLAY 0.638298 (-8697 2625);
PAINT MONO (-8697 2625);
FORCEPROP 2 LAST $XR0 159 
J 0
(-8577 2625);
DISPLAY 0.638298 (-8577 2625);
PAINT MONO (-8577 2625);
FORCEPROP 2 LAST CDS_LIB mstr_standard
J 0
(-8325 2625);
DISPLAY 0.808511 (-8325 2625);
DISPLAY INVISIBLE (-8325 2625);
FORCEPROP 1 LAST OFFPAGE TRUE
J 0
(-8000 2500);
DISPLAY 0.872340 (-8000 2500);
PAINT GREEN (-8000 2500);
DISPLAY INVISIBLE (-8000 2500);
FORCEPROP 1 LAST COMMENT_BODY TRUE
J 0
(-8200 2525);
DISPLAY 0.872340 (-8200 2525);
PAINT GREEN (-8200 2525);
DISPLAY INVISIBLE (-8200 2525);
FORCEPROP 2 LAST PATH I243
J 0
(-8600 2675);
DISPLAY 0.680851 (-8600 2675);
DISPLAY INVISIBLE (-8600 2675);
FORCEADD Q_RES..1
(-7700 2625);
FORCEPROP 1 LAST LOCATION R1587
J 0
(-7750 2650);
DISPLAY 0.510638 (-7750 2650);
PAINT SKYBLUE (-7750 2650);
FORCEPROP 0 LAST $SEC 1
J 0
(-7750 2725);
DISPLAY 0.680851 (-7750 2725);
PAINT MONO (-7750 2725);
DISPLAY INVISIBLE (-7750 2725);
FORCEPROP 0 LAST CDS_SEC 1
J 0
(-7750 2725);
DISPLAY 0.680851 (-7750 2725);
DISPLAY INVISIBLE (-7750 2725);
FORCEPROP 1 LASTPIN (-7800 2625) $PN 1
J 0
(-7788 2637);
DISPLAY 0.787234 (-7788 2637);
PAINT MONO (-7788 2637);
FORCEPROP 1 LASTPIN (-7600 2625) $PN 2
J 0
(-7638 2637);
DISPLAY 0.787234 (-7638 2637);
PAINT MONO (-7638 2637);
FORCEPROP 1 LAST VALUE 49.9
J 2
(-7525 2675);
DISPLAY 0.510638 (-7525 2675);
PAINT SKYBLUE (-7525 2675);
FORCEPROP 2 LAST CDS_LIB pure_quanta
J 0
(-7700 2625);
DISPLAY INVISIBLE (-7700 2625);
FORCEPROP 1 LAST MATERIAL CHIP
J 0
(-7700 2475);
DISPLAY 0.978723 (-7700 2475);
DISPLAY INVISIBLE (-7700 2475);
FORCEPROP 1 LAST PACK_TYPE 0402LF
J 0
(-7450 2475);
DISPLAY 0.978723 (-7450 2475);
DISPLAY INVISIBLE (-7450 2475);
FORCEPROP 1 LAST WATTAGE 1/16W
J 2
(-7725 2475);
DISPLAY 0.978723 (-7725 2475);
DISPLAY INVISIBLE (-7725 2475);
FORCEPROP 1 LAST TOLERANCE 1%
J 0
(-7700 2525);
DISPLAY 0.978723 (-7700 2525);
DISPLAY INVISIBLE (-7700 2525);
FORCEPROP 1 LAST PATH I244
J 0
(-7750 2775);
DISPLAY 0.978723 (-7750 2775);
PAINT WHITE (-7750 2775);
DISPLAY INVISIBLE (-7750 2775);
FORCEPROP 1 LAST PART_NUMBER CS04992FB07
J 0
(-7750 2725);
DISPLAY 0.978723 (-7750 2725);
DISPLAY INVISIBLE (-7750 2725);
FORCEADD Q_RES..1
(-8050 2850);
FORCEPROP 1 LAST LOCATION R1707
J 0
(-8250 2850);
DISPLAY 0.638298 (-8250 2850);
FORCEPROP 0 LAST $SEC 1
J 0
(-8250 2900);
DISPLAY 0.680851 (-8250 2900);
PAINT MONO (-8250 2900);
DISPLAY INVISIBLE (-8250 2900);
FORCEPROP 0 LAST CDS_SEC 1
J 0
(-8250 2900);
DISPLAY 0.680851 (-8250 2900);
DISPLAY INVISIBLE (-8250 2900);
FORCEPROP 1 LASTPIN (-8150 2850) $PN 1
J 0
(-8138 2862);
DISPLAY 0.787234 (-8138 2862);
PAINT MONO (-8138 2862);
FORCEPROP 1 LASTPIN (-7950 2850) $PN 2
J 0
(-7988 2862);
DISPLAY 0.787234 (-7988 2862);
PAINT MONO (-7988 2862);
FORCEPROP 1 LAST VALUE 10
J 2
(-7900 2850);
DISPLAY 0.404255 (-7900 2850);
FORCEPROP 1 LAST PACK_TYPE 0402LF
J 0
(-8000 2825);
DISPLAY 0.404255 (-8000 2825);
FORCEPROP 1 LAST MATERIAL CHIP
J 0
(-8150 2825);
DISPLAY 0.404255 (-8150 2825);
FORCEPROP 2 LAST CDS_LIB pure_quanta
J 0
(-8050 2850);
DISPLAY INVISIBLE (-8050 2850);
FORCEPROP 1 LAST WATTAGE 1/16W
J 2
(-8075 2700);
DISPLAY 0.978723 (-8075 2700);
DISPLAY INVISIBLE (-8075 2700);
FORCEPROP 1 LAST TOLERANCE 1%
J 0
(-8050 2750);
DISPLAY 0.978723 (-8050 2750);
DISPLAY INVISIBLE (-8050 2750);
FORCEPROP 1 LAST PATH I245
J 0
(-8100 3000);
DISPLAY 0.978723 (-8100 3000);
PAINT WHITE (-8100 3000);
DISPLAY INVISIBLE (-8100 3000);
FORCEPROP 1 LAST PART_NUMBER CS01002FB07
J 0
(-8100 2950);
DISPLAY 0.978723 (-8100 2950);
DISPLAY INVISIBLE (-8100 2950);
FORCEADD OFFPAGE..6
(-8725 2725);
FORCEPROP 2 LAST $XR5 159 
J 0
(-9275 2689);
DISPLAY 0.638298 (-9275 2689);
PAINT MONO (-9275 2689);
FORCEPROP 2 LAST $XR4 109 
J 0
(-9155 2689);
DISPLAY 0.638298 (-9155 2689);
PAINT MONO (-9155 2689);
FORCEPROP 2 LAST $XR3 108 
J 0
(-9035 2689);
DISPLAY 0.638298 (-9035 2689);
PAINT MONO (-9035 2689);
FORCEPROP 2 LAST $XR2 107 
J 0
(-9275 2725);
DISPLAY 0.638298 (-9275 2725);
PAINT MONO (-9275 2725);
FORCEPROP 2 LAST $XR1 106 
J 0
(-9155 2725);
DISPLAY 0.638298 (-9155 2725);
PAINT MONO (-9155 2725);
FORCEPROP 2 LAST $XR0 104 
J 0
(-9035 2725);
DISPLAY 0.638298 (-9035 2725);
PAINT MONO (-9035 2725);
FORCEPROP 2 LAST CDS_LIB mstr_standard
J 0
(-8725 2725);
DISPLAY 0.808511 (-8725 2725);
DISPLAY INVISIBLE (-8725 2725);
FORCEPROP 1 LAST OFFPAGE TRUE
J 0
(-8400 2600);
DISPLAY 0.872340 (-8400 2600);
PAINT GREEN (-8400 2600);
DISPLAY INVISIBLE (-8400 2600);
FORCEPROP 1 LAST COMMENT_BODY TRUE
J 0
(-8625 2650);
DISPLAY 0.872340 (-8625 2650);
PAINT GREEN (-8625 2650);
DISPLAY INVISIBLE (-8625 2650);
FORCEPROP 2 LAST PATH I246
J 0
(-9000 2775);
DISPLAY 0.680851 (-9000 2775);
DISPLAY INVISIBLE (-9000 2775);
FORCEADD TAP..1
R 2
(-7650 3250);
FORCEPROP 3 LASTPIN (-7600 3250) SIG_NAME M_H_CPU1_SB_CB<1>
J 0
(-7590 3260);
DISPLAY 0.659574 (-7590 3260);
PAINT MONO (-7590 3260);
DISPLAY INVISIBLE (-7590 3260);
FORCEPROP 1 LASTPIN (-7600 3250) BN 1
J 2
(-7588 3258);
DISPLAY 0.489362 (-7588 3258);
PAINT GREEN (-7588 3258);
FORCEPROP 2 LAST CDS_LIB mstr_standard
J 0
(-7650 3250);
DISPLAY 0.723404 (-7650 3250);
PAINT MONO (-7650 3250);
DISPLAY INVISIBLE (-7650 3250);
FORCEPROP 1 LAST BODY_TYPE PLUMBING
J 2
(-7650 3300);
DISPLAY 0.872340 (-7650 3300);
PAINT GREEN (-7650 3300);
DISPLAY INVISIBLE (-7650 3300);
FORCEPROP 1 LAST HDL_TAP TRUE
J 2
(-7975 3125);
DISPLAY 0.872340 (-7975 3125);
DISPLAY INVISIBLE (-7975 3125);
FORCEPROP 1 LAST PATH I25
J 2
(-7648 3250);
DISPLAY 0.872340 (-7648 3250);
PAINT GREEN (-7648 3250);
DISPLAY INVISIBLE (-7648 3250);
FORCEADD TAP..1
R 2
(-7650 3200);
FORCEPROP 3 LASTPIN (-7600 3200) SIG_NAME M_H_CPU1_SB_CB<0>
J 0
(-7590 3210);
DISPLAY 0.659574 (-7590 3210);
PAINT MONO (-7590 3210);
DISPLAY INVISIBLE (-7590 3210);
FORCEPROP 1 LASTPIN (-7600 3200) BN 0
J 2
(-7588 3208);
DISPLAY 0.489362 (-7588 3208);
PAINT GREEN (-7588 3208);
FORCEPROP 2 LAST CDS_LIB mstr_standard
J 0
(-7650 3200);
DISPLAY 0.723404 (-7650 3200);
PAINT MONO (-7650 3200);
DISPLAY INVISIBLE (-7650 3200);
FORCEPROP 1 LAST BODY_TYPE PLUMBING
J 2
(-7650 3250);
DISPLAY 0.872340 (-7650 3250);
PAINT GREEN (-7650 3250);
DISPLAY INVISIBLE (-7650 3250);
FORCEPROP 1 LAST HDL_TAP TRUE
J 2
(-7975 3075);
DISPLAY 0.872340 (-7975 3075);
DISPLAY INVISIBLE (-7975 3075);
FORCEPROP 1 LAST PATH I26
J 2
(-7648 3200);
DISPLAY 0.872340 (-7648 3200);
PAINT GREEN (-7648 3200);
DISPLAY INVISIBLE (-7648 3200);
FORCEADD TAP..1
R 2
(-7650 3400);
FORCEPROP 3 LASTPIN (-7600 3400) SIG_NAME M_H_CPU1_SB_CB<4>
J 0
(-7590 3410);
DISPLAY 0.659574 (-7590 3410);
PAINT MONO (-7590 3410);
DISPLAY INVISIBLE (-7590 3410);
FORCEPROP 1 LASTPIN (-7600 3400) BN 4
J 2
(-7588 3408);
DISPLAY 0.489362 (-7588 3408);
PAINT GREEN (-7588 3408);
FORCEPROP 2 LAST CDS_LIB mstr_standard
J 0
(-7650 3400);
DISPLAY 0.723404 (-7650 3400);
PAINT MONO (-7650 3400);
DISPLAY INVISIBLE (-7650 3400);
FORCEPROP 1 LAST BODY_TYPE PLUMBING
J 2
(-7650 3450);
DISPLAY 0.872340 (-7650 3450);
PAINT GREEN (-7650 3450);
DISPLAY INVISIBLE (-7650 3450);
FORCEPROP 1 LAST HDL_TAP TRUE
J 2
(-7975 3275);
DISPLAY 0.872340 (-7975 3275);
DISPLAY INVISIBLE (-7975 3275);
FORCEPROP 1 LAST PATH I27
J 2
(-7648 3400);
DISPLAY 0.872340 (-7648 3400);
PAINT GREEN (-7648 3400);
DISPLAY INVISIBLE (-7648 3400);
FORCEADD TAP..1
R 2
(-7650 3450);
FORCEPROP 3 LASTPIN (-7600 3450) SIG_NAME M_H_CPU1_SB_CB<5>
J 0
(-7590 3460);
DISPLAY 0.659574 (-7590 3460);
PAINT MONO (-7590 3460);
DISPLAY INVISIBLE (-7590 3460);
FORCEPROP 1 LASTPIN (-7600 3450) BN 5
J 2
(-7588 3458);
DISPLAY 0.489362 (-7588 3458);
PAINT GREEN (-7588 3458);
FORCEPROP 2 LAST CDS_LIB mstr_standard
J 0
(-7650 3450);
DISPLAY 0.723404 (-7650 3450);
PAINT MONO (-7650 3450);
DISPLAY INVISIBLE (-7650 3450);
FORCEPROP 1 LAST BODY_TYPE PLUMBING
J 2
(-7650 3500);
DISPLAY 0.872340 (-7650 3500);
PAINT GREEN (-7650 3500);
DISPLAY INVISIBLE (-7650 3500);
FORCEPROP 1 LAST HDL_TAP TRUE
J 2
(-7975 3325);
DISPLAY 0.872340 (-7975 3325);
DISPLAY INVISIBLE (-7975 3325);
FORCEPROP 1 LAST PATH I28
J 2
(-7648 3450);
DISPLAY 0.872340 (-7648 3450);
PAINT GREEN (-7648 3450);
DISPLAY INVISIBLE (-7648 3450);
FORCEADD TAP..1
R 2
(-7650 3500);
FORCEPROP 3 LASTPIN (-7600 3500) SIG_NAME M_H_CPU1_SB_CB<6>
J 0
(-7590 3510);
DISPLAY 0.659574 (-7590 3510);
PAINT MONO (-7590 3510);
DISPLAY INVISIBLE (-7590 3510);
FORCEPROP 1 LASTPIN (-7600 3500) BN 6
J 2
(-7588 3508);
DISPLAY 0.489362 (-7588 3508);
PAINT GREEN (-7588 3508);
FORCEPROP 2 LAST CDS_LIB mstr_standard
J 0
(-7650 3500);
DISPLAY 0.723404 (-7650 3500);
PAINT MONO (-7650 3500);
DISPLAY INVISIBLE (-7650 3500);
FORCEPROP 1 LAST BODY_TYPE PLUMBING
J 2
(-7650 3550);
DISPLAY 0.872340 (-7650 3550);
PAINT GREEN (-7650 3550);
DISPLAY INVISIBLE (-7650 3550);
FORCEPROP 1 LAST HDL_TAP TRUE
J 2
(-7975 3375);
DISPLAY 0.872340 (-7975 3375);
DISPLAY INVISIBLE (-7975 3375);
FORCEPROP 1 LAST PATH I29
J 2
(-7648 3500);
DISPLAY 0.872340 (-7648 3500);
PAINT GREEN (-7648 3500);
DISPLAY INVISIBLE (-7648 3500);
FORCEADD TAP..1
R 2
(-7650 3550);
FORCEPROP 3 LASTPIN (-7600 3550) SIG_NAME M_H_CPU1_SB_CB<7>
J 0
(-7590 3560);
DISPLAY 0.659574 (-7590 3560);
PAINT MONO (-7590 3560);
DISPLAY INVISIBLE (-7590 3560);
FORCEPROP 1 LASTPIN (-7600 3550) BN 7
J 2
(-7588 3558);
DISPLAY 0.489362 (-7588 3558);
PAINT GREEN (-7588 3558);
FORCEPROP 2 LAST CDS_LIB mstr_standard
J 0
(-7650 3550);
DISPLAY 0.723404 (-7650 3550);
PAINT MONO (-7650 3550);
DISPLAY INVISIBLE (-7650 3550);
FORCEPROP 1 LAST BODY_TYPE PLUMBING
J 2
(-7650 3600);
DISPLAY 0.872340 (-7650 3600);
PAINT GREEN (-7650 3600);
DISPLAY INVISIBLE (-7650 3600);
FORCEPROP 1 LAST HDL_TAP TRUE
J 2
(-7975 3425);
DISPLAY 0.872340 (-7975 3425);
DISPLAY INVISIBLE (-7975 3425);
FORCEPROP 1 LAST PATH I30
J 2
(-7648 3550);
DISPLAY 0.872340 (-7648 3550);
PAINT GREEN (-7648 3550);
DISPLAY INVISIBLE (-7648 3550);
FORCEADD TAP..1
R 2
(-7650 3650);
FORCEPROP 3 LASTPIN (-7600 3650) SIG_NAME M_H_CPU1_SA_CB<0>
J 0
(-7590 3660);
DISPLAY 0.659574 (-7590 3660);
PAINT MONO (-7590 3660);
DISPLAY INVISIBLE (-7590 3660);
FORCEPROP 1 LASTPIN (-7600 3650) BN 0
J 2
(-7588 3658);
DISPLAY 0.489362 (-7588 3658);
PAINT GREEN (-7588 3658);
FORCEPROP 2 LAST CDS_LIB mstr_standard
J 0
(-7650 3650);
DISPLAY 0.723404 (-7650 3650);
PAINT MONO (-7650 3650);
DISPLAY INVISIBLE (-7650 3650);
FORCEPROP 1 LAST BODY_TYPE PLUMBING
J 2
(-7650 3700);
DISPLAY 0.872340 (-7650 3700);
PAINT GREEN (-7650 3700);
DISPLAY INVISIBLE (-7650 3700);
FORCEPROP 1 LAST HDL_TAP TRUE
J 2
(-7975 3525);
DISPLAY 0.872340 (-7975 3525);
DISPLAY INVISIBLE (-7975 3525);
FORCEPROP 1 LAST PATH I31
J 2
(-7648 3650);
DISPLAY 0.872340 (-7648 3650);
PAINT GREEN (-7648 3650);
DISPLAY INVISIBLE (-7648 3650);
FORCEADD TAP..1
R 2
(-7650 3700);
FORCEPROP 3 LASTPIN (-7600 3700) SIG_NAME M_H_CPU1_SA_CB<1>
J 0
(-7590 3710);
DISPLAY 0.659574 (-7590 3710);
PAINT MONO (-7590 3710);
DISPLAY INVISIBLE (-7590 3710);
FORCEPROP 1 LASTPIN (-7600 3700) BN 1
J 2
(-7588 3708);
DISPLAY 0.489362 (-7588 3708);
PAINT GREEN (-7588 3708);
FORCEPROP 2 LAST CDS_LIB mstr_standard
J 0
(-7650 3700);
DISPLAY 0.723404 (-7650 3700);
PAINT MONO (-7650 3700);
DISPLAY INVISIBLE (-7650 3700);
FORCEPROP 1 LAST BODY_TYPE PLUMBING
J 2
(-7650 3750);
DISPLAY 0.872340 (-7650 3750);
PAINT GREEN (-7650 3750);
DISPLAY INVISIBLE (-7650 3750);
FORCEPROP 1 LAST HDL_TAP TRUE
J 2
(-7975 3575);
DISPLAY 0.872340 (-7975 3575);
DISPLAY INVISIBLE (-7975 3575);
FORCEPROP 1 LAST PATH I32
J 2
(-7648 3700);
DISPLAY 0.872340 (-7648 3700);
PAINT GREEN (-7648 3700);
DISPLAY INVISIBLE (-7648 3700);
FORCEADD TAP..1
R 2
(-7650 3750);
FORCEPROP 3 LASTPIN (-7600 3750) SIG_NAME M_H_CPU1_SA_CB<2>
J 0
(-7590 3760);
DISPLAY 0.659574 (-7590 3760);
PAINT MONO (-7590 3760);
DISPLAY INVISIBLE (-7590 3760);
FORCEPROP 1 LASTPIN (-7600 3750) BN 2
J 2
(-7588 3758);
DISPLAY 0.489362 (-7588 3758);
PAINT GREEN (-7588 3758);
FORCEPROP 2 LAST CDS_LIB mstr_standard
J 0
(-7650 3750);
DISPLAY 0.723404 (-7650 3750);
PAINT MONO (-7650 3750);
DISPLAY INVISIBLE (-7650 3750);
FORCEPROP 1 LAST BODY_TYPE PLUMBING
J 2
(-7650 3800);
DISPLAY 0.872340 (-7650 3800);
PAINT GREEN (-7650 3800);
DISPLAY INVISIBLE (-7650 3800);
FORCEPROP 1 LAST HDL_TAP TRUE
J 2
(-7975 3625);
DISPLAY 0.872340 (-7975 3625);
DISPLAY INVISIBLE (-7975 3625);
FORCEPROP 1 LAST PATH I33
J 2
(-7648 3750);
DISPLAY 0.872340 (-7648 3750);
PAINT GREEN (-7648 3750);
DISPLAY INVISIBLE (-7648 3750);
FORCEADD TAP..1
R 2
(-7650 3800);
FORCEPROP 3 LASTPIN (-7600 3800) SIG_NAME M_H_CPU1_SA_CB<3>
J 0
(-7590 3810);
DISPLAY 0.659574 (-7590 3810);
PAINT MONO (-7590 3810);
DISPLAY INVISIBLE (-7590 3810);
FORCEPROP 1 LASTPIN (-7600 3800) BN 3
J 2
(-7588 3808);
DISPLAY 0.489362 (-7588 3808);
PAINT GREEN (-7588 3808);
FORCEPROP 2 LAST CDS_LIB mstr_standard
J 0
(-7650 3800);
DISPLAY 0.723404 (-7650 3800);
PAINT MONO (-7650 3800);
DISPLAY INVISIBLE (-7650 3800);
FORCEPROP 1 LAST BODY_TYPE PLUMBING
J 2
(-7650 3850);
DISPLAY 0.872340 (-7650 3850);
PAINT GREEN (-7650 3850);
DISPLAY INVISIBLE (-7650 3850);
FORCEPROP 1 LAST HDL_TAP TRUE
J 2
(-7975 3675);
DISPLAY 0.872340 (-7975 3675);
DISPLAY INVISIBLE (-7975 3675);
FORCEPROP 1 LAST PATH I34
J 2
(-7648 3800);
DISPLAY 0.872340 (-7648 3800);
PAINT GREEN (-7648 3800);
DISPLAY INVISIBLE (-7648 3800);
FORCEADD TAP..1
R 2
(-7650 3850);
FORCEPROP 3 LASTPIN (-7600 3850) SIG_NAME M_H_CPU1_SA_CB<4>
J 0
(-7590 3860);
DISPLAY 0.659574 (-7590 3860);
PAINT MONO (-7590 3860);
DISPLAY INVISIBLE (-7590 3860);
FORCEPROP 1 LASTPIN (-7600 3850) BN 4
J 2
(-7588 3858);
DISPLAY 0.489362 (-7588 3858);
PAINT GREEN (-7588 3858);
FORCEPROP 2 LAST CDS_LIB mstr_standard
J 0
(-7650 3850);
DISPLAY 0.723404 (-7650 3850);
PAINT MONO (-7650 3850);
DISPLAY INVISIBLE (-7650 3850);
FORCEPROP 1 LAST BODY_TYPE PLUMBING
J 2
(-7650 3900);
DISPLAY 0.872340 (-7650 3900);
PAINT GREEN (-7650 3900);
DISPLAY INVISIBLE (-7650 3900);
FORCEPROP 1 LAST HDL_TAP TRUE
J 2
(-7975 3725);
DISPLAY 0.872340 (-7975 3725);
DISPLAY INVISIBLE (-7975 3725);
FORCEPROP 1 LAST PATH I35
J 2
(-7648 3850);
DISPLAY 0.872340 (-7648 3850);
PAINT GREEN (-7648 3850);
DISPLAY INVISIBLE (-7648 3850);
FORCEADD TAP..1
(-5950 2200);
FORCEPROP 3 LASTPIN (-6000 2200) SIG_NAME M_H_CPU1_SB_DQ<0>
J 0
(-5990 2210);
DISPLAY 0.659574 (-5990 2210);
PAINT MONO (-5990 2210);
DISPLAY INVISIBLE (-5990 2210);
FORCEPROP 1 LASTPIN (-6000 2200) BN 0
J 0
(-6012 2208);
DISPLAY 0.489362 (-6012 2208);
PAINT GREEN (-6012 2208);
FORCEPROP 2 LAST CDS_LIB mstr_standard
J 0
(-5950 2200);
DISPLAY 0.723404 (-5950 2200);
PAINT MONO (-5950 2200);
DISPLAY INVISIBLE (-5950 2200);
FORCEPROP 1 LAST BODY_TYPE PLUMBING
J 0
(-5950 2250);
DISPLAY 0.872340 (-5950 2250);
PAINT GREEN (-5950 2250);
DISPLAY INVISIBLE (-5950 2250);
FORCEPROP 1 LAST HDL_TAP TRUE
J 0
(-5625 2075);
DISPLAY 0.872340 (-5625 2075);
DISPLAY INVISIBLE (-5625 2075);
FORCEPROP 1 LAST PATH I36
J 0
(-5952 2200);
DISPLAY 0.872340 (-5952 2200);
PAINT GREEN (-5952 2200);
DISPLAY INVISIBLE (-5952 2200);
FORCEADD TAP..1
(-5950 2300);
FORCEPROP 3 LASTPIN (-6000 2300) SIG_NAME M_H_CPU1_SB_DQ<2>
J 0
(-5990 2310);
DISPLAY 0.659574 (-5990 2310);
PAINT MONO (-5990 2310);
DISPLAY INVISIBLE (-5990 2310);
FORCEPROP 1 LASTPIN (-6000 2300) BN 2
J 0
(-6012 2308);
DISPLAY 0.489362 (-6012 2308);
PAINT GREEN (-6012 2308);
FORCEPROP 2 LAST CDS_LIB mstr_standard
J 0
(-5950 2300);
DISPLAY 0.723404 (-5950 2300);
PAINT MONO (-5950 2300);
DISPLAY INVISIBLE (-5950 2300);
FORCEPROP 1 LAST BODY_TYPE PLUMBING
J 0
(-5950 2350);
DISPLAY 0.872340 (-5950 2350);
PAINT GREEN (-5950 2350);
DISPLAY INVISIBLE (-5950 2350);
FORCEPROP 1 LAST HDL_TAP TRUE
J 0
(-5625 2175);
DISPLAY 0.872340 (-5625 2175);
DISPLAY INVISIBLE (-5625 2175);
FORCEPROP 1 LAST PATH I37
J 0
(-5952 2300);
DISPLAY 0.872340 (-5952 2300);
PAINT GREEN (-5952 2300);
DISPLAY INVISIBLE (-5952 2300);
FORCEADD TAP..1
(-5950 2350);
FORCEPROP 3 LASTPIN (-6000 2350) SIG_NAME M_H_CPU1_SB_DQ<3>
J 0
(-5990 2360);
DISPLAY 0.659574 (-5990 2360);
PAINT MONO (-5990 2360);
DISPLAY INVISIBLE (-5990 2360);
FORCEPROP 1 LASTPIN (-6000 2350) BN 3
J 0
(-6012 2358);
DISPLAY 0.489362 (-6012 2358);
PAINT GREEN (-6012 2358);
FORCEPROP 2 LAST CDS_LIB mstr_standard
J 0
(-5950 2350);
DISPLAY 0.723404 (-5950 2350);
PAINT MONO (-5950 2350);
DISPLAY INVISIBLE (-5950 2350);
FORCEPROP 1 LAST BODY_TYPE PLUMBING
J 0
(-5950 2400);
DISPLAY 0.872340 (-5950 2400);
PAINT GREEN (-5950 2400);
DISPLAY INVISIBLE (-5950 2400);
FORCEPROP 1 LAST HDL_TAP TRUE
J 0
(-5625 2225);
DISPLAY 0.872340 (-5625 2225);
DISPLAY INVISIBLE (-5625 2225);
FORCEPROP 1 LAST PATH I38
J 0
(-5952 2350);
DISPLAY 0.872340 (-5952 2350);
PAINT GREEN (-5952 2350);
DISPLAY INVISIBLE (-5952 2350);
FORCEADD TAP..1
(-5950 2250);
FORCEPROP 3 LASTPIN (-6000 2250) SIG_NAME M_H_CPU1_SB_DQ<1>
J 0
(-5990 2260);
DISPLAY 0.659574 (-5990 2260);
PAINT MONO (-5990 2260);
DISPLAY INVISIBLE (-5990 2260);
FORCEPROP 1 LASTPIN (-6000 2250) BN 1
J 0
(-6012 2258);
DISPLAY 0.489362 (-6012 2258);
PAINT GREEN (-6012 2258);
FORCEPROP 2 LAST CDS_LIB mstr_standard
J 0
(-5950 2250);
DISPLAY 0.723404 (-5950 2250);
PAINT MONO (-5950 2250);
DISPLAY INVISIBLE (-5950 2250);
FORCEPROP 1 LAST BODY_TYPE PLUMBING
J 0
(-5950 2300);
DISPLAY 0.872340 (-5950 2300);
PAINT GREEN (-5950 2300);
DISPLAY INVISIBLE (-5950 2300);
FORCEPROP 1 LAST HDL_TAP TRUE
J 0
(-5625 2125);
DISPLAY 0.872340 (-5625 2125);
DISPLAY INVISIBLE (-5625 2125);
FORCEPROP 1 LAST PATH I39
J 0
(-5952 2250);
DISPLAY 0.872340 (-5952 2250);
PAINT GREEN (-5952 2250);
DISPLAY INVISIBLE (-5952 2250);
FORCEADD TAP..1
(-5950 2400);
FORCEPROP 3 LASTPIN (-6000 2400) SIG_NAME M_H_CPU1_SB_DQ<4>
J 0
(-5990 2410);
DISPLAY 0.659574 (-5990 2410);
PAINT MONO (-5990 2410);
DISPLAY INVISIBLE (-5990 2410);
FORCEPROP 1 LASTPIN (-6000 2400) BN 4
J 0
(-6012 2408);
DISPLAY 0.489362 (-6012 2408);
PAINT GREEN (-6012 2408);
FORCEPROP 2 LAST CDS_LIB mstr_standard
J 0
(-5950 2400);
DISPLAY 0.723404 (-5950 2400);
PAINT MONO (-5950 2400);
DISPLAY INVISIBLE (-5950 2400);
FORCEPROP 1 LAST BODY_TYPE PLUMBING
J 0
(-5950 2450);
DISPLAY 0.872340 (-5950 2450);
PAINT GREEN (-5950 2450);
DISPLAY INVISIBLE (-5950 2450);
FORCEPROP 1 LAST HDL_TAP TRUE
J 0
(-5625 2275);
DISPLAY 0.872340 (-5625 2275);
DISPLAY INVISIBLE (-5625 2275);
FORCEPROP 1 LAST PATH I40
J 0
(-5952 2400);
DISPLAY 0.872340 (-5952 2400);
PAINT GREEN (-5952 2400);
DISPLAY INVISIBLE (-5952 2400);
FORCEADD TAP..1
(-5950 2450);
FORCEPROP 3 LASTPIN (-6000 2450) SIG_NAME M_H_CPU1_SB_DQ<5>
J 0
(-5990 2460);
DISPLAY 0.659574 (-5990 2460);
PAINT MONO (-5990 2460);
DISPLAY INVISIBLE (-5990 2460);
FORCEPROP 1 LASTPIN (-6000 2450) BN 5
J 0
(-6012 2458);
DISPLAY 0.489362 (-6012 2458);
PAINT GREEN (-6012 2458);
FORCEPROP 2 LAST CDS_LIB mstr_standard
J 0
(-5950 2450);
DISPLAY 0.723404 (-5950 2450);
PAINT MONO (-5950 2450);
DISPLAY INVISIBLE (-5950 2450);
FORCEPROP 1 LAST BODY_TYPE PLUMBING
J 0
(-5950 2500);
DISPLAY 0.872340 (-5950 2500);
PAINT GREEN (-5950 2500);
DISPLAY INVISIBLE (-5950 2500);
FORCEPROP 1 LAST HDL_TAP TRUE
J 0
(-5625 2325);
DISPLAY 0.872340 (-5625 2325);
DISPLAY INVISIBLE (-5625 2325);
FORCEPROP 1 LAST PATH I41
J 0
(-5952 2450);
DISPLAY 0.872340 (-5952 2450);
PAINT GREEN (-5952 2450);
DISPLAY INVISIBLE (-5952 2450);
FORCEADD TAP..1
(-5950 2500);
FORCEPROP 3 LASTPIN (-6000 2500) SIG_NAME M_H_CPU1_SB_DQ<6>
J 0
(-5990 2510);
DISPLAY 0.659574 (-5990 2510);
PAINT MONO (-5990 2510);
DISPLAY INVISIBLE (-5990 2510);
FORCEPROP 1 LASTPIN (-6000 2500) BN 6
J 0
(-6012 2508);
DISPLAY 0.489362 (-6012 2508);
PAINT GREEN (-6012 2508);
FORCEPROP 2 LAST CDS_LIB mstr_standard
J 0
(-5950 2500);
DISPLAY 0.723404 (-5950 2500);
PAINT MONO (-5950 2500);
DISPLAY INVISIBLE (-5950 2500);
FORCEPROP 1 LAST BODY_TYPE PLUMBING
J 0
(-5950 2550);
DISPLAY 0.872340 (-5950 2550);
PAINT GREEN (-5950 2550);
DISPLAY INVISIBLE (-5950 2550);
FORCEPROP 1 LAST HDL_TAP TRUE
J 0
(-5625 2375);
DISPLAY 0.872340 (-5625 2375);
DISPLAY INVISIBLE (-5625 2375);
FORCEPROP 1 LAST PATH I42
J 0
(-5952 2500);
DISPLAY 0.872340 (-5952 2500);
PAINT GREEN (-5952 2500);
DISPLAY INVISIBLE (-5952 2500);
FORCEADD TAP..1
(-5950 2550);
FORCEPROP 3 LASTPIN (-6000 2550) SIG_NAME M_H_CPU1_SB_DQ<7>
J 0
(-5990 2560);
DISPLAY 0.659574 (-5990 2560);
PAINT MONO (-5990 2560);
DISPLAY INVISIBLE (-5990 2560);
FORCEPROP 1 LASTPIN (-6000 2550) BN 7
J 0
(-6012 2558);
DISPLAY 0.489362 (-6012 2558);
PAINT GREEN (-6012 2558);
FORCEPROP 2 LAST CDS_LIB mstr_standard
J 0
(-5950 2550);
DISPLAY 0.723404 (-5950 2550);
PAINT MONO (-5950 2550);
DISPLAY INVISIBLE (-5950 2550);
FORCEPROP 1 LAST BODY_TYPE PLUMBING
J 0
(-5950 2600);
DISPLAY 0.872340 (-5950 2600);
PAINT GREEN (-5950 2600);
DISPLAY INVISIBLE (-5950 2600);
FORCEPROP 1 LAST HDL_TAP TRUE
J 0
(-5625 2425);
DISPLAY 0.872340 (-5625 2425);
DISPLAY INVISIBLE (-5625 2425);
FORCEPROP 1 LAST PATH I43
J 0
(-5952 2550);
DISPLAY 0.872340 (-5952 2550);
PAINT GREEN (-5952 2550);
DISPLAY INVISIBLE (-5952 2550);
FORCEADD TAP..1
(-5950 2600);
FORCEPROP 3 LASTPIN (-6000 2600) SIG_NAME M_H_CPU1_SB_DQ<8>
J 0
(-5990 2610);
DISPLAY 0.659574 (-5990 2610);
PAINT MONO (-5990 2610);
DISPLAY INVISIBLE (-5990 2610);
FORCEPROP 1 LASTPIN (-6000 2600) BN 8
J 0
(-6012 2608);
DISPLAY 0.489362 (-6012 2608);
PAINT GREEN (-6012 2608);
FORCEPROP 2 LAST CDS_LIB mstr_standard
J 0
(-5950 2600);
DISPLAY 0.723404 (-5950 2600);
PAINT MONO (-5950 2600);
DISPLAY INVISIBLE (-5950 2600);
FORCEPROP 1 LAST BODY_TYPE PLUMBING
J 0
(-5950 2650);
DISPLAY 0.872340 (-5950 2650);
PAINT GREEN (-5950 2650);
DISPLAY INVISIBLE (-5950 2650);
FORCEPROP 1 LAST HDL_TAP TRUE
J 0
(-5625 2475);
DISPLAY 0.872340 (-5625 2475);
DISPLAY INVISIBLE (-5625 2475);
FORCEPROP 1 LAST PATH I44
J 0
(-5952 2600);
DISPLAY 0.872340 (-5952 2600);
PAINT GREEN (-5952 2600);
DISPLAY INVISIBLE (-5952 2600);
FORCEADD TAP..1
(-5950 2650);
FORCEPROP 3 LASTPIN (-6000 2650) SIG_NAME M_H_CPU1_SB_DQ<9>
J 0
(-5990 2660);
DISPLAY 0.659574 (-5990 2660);
PAINT MONO (-5990 2660);
DISPLAY INVISIBLE (-5990 2660);
FORCEPROP 1 LASTPIN (-6000 2650) BN 9
J 0
(-6012 2658);
DISPLAY 0.489362 (-6012 2658);
PAINT GREEN (-6012 2658);
FORCEPROP 2 LAST CDS_LIB mstr_standard
J 0
(-5950 2650);
DISPLAY 0.723404 (-5950 2650);
PAINT MONO (-5950 2650);
DISPLAY INVISIBLE (-5950 2650);
FORCEPROP 1 LAST BODY_TYPE PLUMBING
J 0
(-5950 2700);
DISPLAY 0.872340 (-5950 2700);
PAINT GREEN (-5950 2700);
DISPLAY INVISIBLE (-5950 2700);
FORCEPROP 1 LAST HDL_TAP TRUE
J 0
(-5625 2525);
DISPLAY 0.872340 (-5625 2525);
DISPLAY INVISIBLE (-5625 2525);
FORCEPROP 1 LAST PATH I45
J 0
(-5952 2650);
DISPLAY 0.872340 (-5952 2650);
PAINT GREEN (-5952 2650);
DISPLAY INVISIBLE (-5952 2650);
FORCEADD TAP..1
(-5950 2700);
FORCEPROP 3 LASTPIN (-6000 2700) SIG_NAME M_H_CPU1_SB_DQ<10>
J 0
(-5990 2710);
DISPLAY 0.659574 (-5990 2710);
PAINT MONO (-5990 2710);
DISPLAY INVISIBLE (-5990 2710);
FORCEPROP 1 LASTPIN (-6000 2700) BN 10
J 0
(-6012 2708);
DISPLAY 0.489362 (-6012 2708);
PAINT GREEN (-6012 2708);
FORCEPROP 2 LAST CDS_LIB mstr_standard
J 0
(-5950 2700);
DISPLAY 0.723404 (-5950 2700);
PAINT MONO (-5950 2700);
DISPLAY INVISIBLE (-5950 2700);
FORCEPROP 1 LAST BODY_TYPE PLUMBING
J 0
(-5950 2750);
DISPLAY 0.872340 (-5950 2750);
PAINT GREEN (-5950 2750);
DISPLAY INVISIBLE (-5950 2750);
FORCEPROP 1 LAST HDL_TAP TRUE
J 0
(-5625 2575);
DISPLAY 0.872340 (-5625 2575);
DISPLAY INVISIBLE (-5625 2575);
FORCEPROP 1 LAST PATH I46
J 0
(-5952 2700);
DISPLAY 0.872340 (-5952 2700);
PAINT GREEN (-5952 2700);
DISPLAY INVISIBLE (-5952 2700);
FORCEADD TAP..1
(-5950 2750);
FORCEPROP 3 LASTPIN (-6000 2750) SIG_NAME M_H_CPU1_SB_DQ<11>
J 0
(-5990 2760);
DISPLAY 0.659574 (-5990 2760);
PAINT MONO (-5990 2760);
DISPLAY INVISIBLE (-5990 2760);
FORCEPROP 1 LASTPIN (-6000 2750) BN 11
J 0
(-6012 2758);
DISPLAY 0.489362 (-6012 2758);
PAINT GREEN (-6012 2758);
FORCEPROP 2 LAST CDS_LIB mstr_standard
J 0
(-5950 2750);
DISPLAY 0.723404 (-5950 2750);
PAINT MONO (-5950 2750);
DISPLAY INVISIBLE (-5950 2750);
FORCEPROP 1 LAST BODY_TYPE PLUMBING
J 0
(-5950 2800);
DISPLAY 0.872340 (-5950 2800);
PAINT GREEN (-5950 2800);
DISPLAY INVISIBLE (-5950 2800);
FORCEPROP 1 LAST HDL_TAP TRUE
J 0
(-5625 2625);
DISPLAY 0.872340 (-5625 2625);
DISPLAY INVISIBLE (-5625 2625);
FORCEPROP 1 LAST PATH I47
J 0
(-5952 2750);
DISPLAY 0.872340 (-5952 2750);
PAINT GREEN (-5952 2750);
DISPLAY INVISIBLE (-5952 2750);
FORCEADD TAP..1
(-5950 2850);
FORCEPROP 3 LASTPIN (-6000 2850) SIG_NAME M_H_CPU1_SB_DQ<13>
J 0
(-5990 2860);
DISPLAY 0.659574 (-5990 2860);
PAINT MONO (-5990 2860);
DISPLAY INVISIBLE (-5990 2860);
FORCEPROP 1 LASTPIN (-6000 2850) BN 13
J 0
(-6012 2858);
DISPLAY 0.489362 (-6012 2858);
PAINT GREEN (-6012 2858);
FORCEPROP 2 LAST CDS_LIB mstr_standard
J 0
(-5950 2850);
DISPLAY 0.723404 (-5950 2850);
PAINT MONO (-5950 2850);
DISPLAY INVISIBLE (-5950 2850);
FORCEPROP 1 LAST BODY_TYPE PLUMBING
J 0
(-5950 2900);
DISPLAY 0.872340 (-5950 2900);
PAINT GREEN (-5950 2900);
DISPLAY INVISIBLE (-5950 2900);
FORCEPROP 1 LAST HDL_TAP TRUE
J 0
(-5625 2725);
DISPLAY 0.872340 (-5625 2725);
DISPLAY INVISIBLE (-5625 2725);
FORCEPROP 1 LAST PATH I48
J 0
(-5952 2850);
DISPLAY 0.872340 (-5952 2850);
PAINT GREEN (-5952 2850);
DISPLAY INVISIBLE (-5952 2850);
FORCEADD TAP..1
(-5950 2800);
FORCEPROP 3 LASTPIN (-6000 2800) SIG_NAME M_H_CPU1_SB_DQ<12>
J 0
(-5990 2810);
DISPLAY 0.659574 (-5990 2810);
PAINT MONO (-5990 2810);
DISPLAY INVISIBLE (-5990 2810);
FORCEPROP 1 LASTPIN (-6000 2800) BN 12
J 0
(-6012 2808);
DISPLAY 0.489362 (-6012 2808);
PAINT GREEN (-6012 2808);
FORCEPROP 2 LAST CDS_LIB mstr_standard
J 0
(-5950 2800);
DISPLAY 0.723404 (-5950 2800);
PAINT MONO (-5950 2800);
DISPLAY INVISIBLE (-5950 2800);
FORCEPROP 1 LAST BODY_TYPE PLUMBING
J 0
(-5950 2850);
DISPLAY 0.872340 (-5950 2850);
PAINT GREEN (-5950 2850);
DISPLAY INVISIBLE (-5950 2850);
FORCEPROP 1 LAST HDL_TAP TRUE
J 0
(-5625 2675);
DISPLAY 0.872340 (-5625 2675);
DISPLAY INVISIBLE (-5625 2675);
FORCEPROP 1 LAST PATH I49
J 0
(-5952 2800);
DISPLAY 0.872340 (-5952 2800);
PAINT GREEN (-5952 2800);
DISPLAY INVISIBLE (-5952 2800);
FORCEADD TAP..1
(-5950 2900);
FORCEPROP 3 LASTPIN (-6000 2900) SIG_NAME M_H_CPU1_SB_DQ<14>
J 0
(-5990 2910);
DISPLAY 0.659574 (-5990 2910);
PAINT MONO (-5990 2910);
DISPLAY INVISIBLE (-5990 2910);
FORCEPROP 1 LASTPIN (-6000 2900) BN 14
J 0
(-6012 2908);
DISPLAY 0.489362 (-6012 2908);
PAINT GREEN (-6012 2908);
FORCEPROP 2 LAST CDS_LIB mstr_standard
J 0
(-5950 2900);
DISPLAY 0.723404 (-5950 2900);
PAINT MONO (-5950 2900);
DISPLAY INVISIBLE (-5950 2900);
FORCEPROP 1 LAST BODY_TYPE PLUMBING
J 0
(-5950 2950);
DISPLAY 0.872340 (-5950 2950);
PAINT GREEN (-5950 2950);
DISPLAY INVISIBLE (-5950 2950);
FORCEPROP 1 LAST HDL_TAP TRUE
J 0
(-5625 2775);
DISPLAY 0.872340 (-5625 2775);
DISPLAY INVISIBLE (-5625 2775);
FORCEPROP 1 LAST PATH I50
J 0
(-5952 2900);
DISPLAY 0.872340 (-5952 2900);
PAINT GREEN (-5952 2900);
DISPLAY INVISIBLE (-5952 2900);
FORCEADD TAP..1
(-5950 2950);
FORCEPROP 3 LASTPIN (-6000 2950) SIG_NAME M_H_CPU1_SB_DQ<15>
J 0
(-5990 2960);
DISPLAY 0.659574 (-5990 2960);
PAINT MONO (-5990 2960);
DISPLAY INVISIBLE (-5990 2960);
FORCEPROP 1 LASTPIN (-6000 2950) BN 15
J 0
(-6012 2958);
DISPLAY 0.489362 (-6012 2958);
PAINT GREEN (-6012 2958);
FORCEPROP 2 LAST CDS_LIB mstr_standard
J 0
(-5950 2950);
DISPLAY 0.723404 (-5950 2950);
PAINT MONO (-5950 2950);
DISPLAY INVISIBLE (-5950 2950);
FORCEPROP 1 LAST BODY_TYPE PLUMBING
J 0
(-5950 3000);
DISPLAY 0.872340 (-5950 3000);
PAINT GREEN (-5950 3000);
DISPLAY INVISIBLE (-5950 3000);
FORCEPROP 1 LAST HDL_TAP TRUE
J 0
(-5625 2825);
DISPLAY 0.872340 (-5625 2825);
DISPLAY INVISIBLE (-5625 2825);
FORCEPROP 1 LAST PATH I51
J 0
(-5952 2950);
DISPLAY 0.872340 (-5952 2950);
PAINT GREEN (-5952 2950);
DISPLAY INVISIBLE (-5952 2950);
FORCEADD TAP..1
(-5950 3000);
FORCEPROP 3 LASTPIN (-6000 3000) SIG_NAME M_H_CPU1_SB_DQ<16>
J 0
(-5990 3010);
DISPLAY 0.659574 (-5990 3010);
PAINT MONO (-5990 3010);
DISPLAY INVISIBLE (-5990 3010);
FORCEPROP 1 LASTPIN (-6000 3000) BN 16
J 0
(-6012 3008);
DISPLAY 0.489362 (-6012 3008);
PAINT GREEN (-6012 3008);
FORCEPROP 2 LAST CDS_LIB mstr_standard
J 0
(-5950 3000);
DISPLAY 0.723404 (-5950 3000);
PAINT MONO (-5950 3000);
DISPLAY INVISIBLE (-5950 3000);
FORCEPROP 1 LAST BODY_TYPE PLUMBING
J 0
(-5950 3050);
DISPLAY 0.872340 (-5950 3050);
PAINT GREEN (-5950 3050);
DISPLAY INVISIBLE (-5950 3050);
FORCEPROP 1 LAST HDL_TAP TRUE
J 0
(-5625 2875);
DISPLAY 0.872340 (-5625 2875);
DISPLAY INVISIBLE (-5625 2875);
FORCEPROP 1 LAST PATH I52
J 0
(-5952 3000);
DISPLAY 0.872340 (-5952 3000);
PAINT GREEN (-5952 3000);
DISPLAY INVISIBLE (-5952 3000);
FORCEADD TAP..1
(-5950 3050);
FORCEPROP 3 LASTPIN (-6000 3050) SIG_NAME M_H_CPU1_SB_DQ<17>
J 0
(-5990 3060);
DISPLAY 0.659574 (-5990 3060);
PAINT MONO (-5990 3060);
DISPLAY INVISIBLE (-5990 3060);
FORCEPROP 1 LASTPIN (-6000 3050) BN 17
J 0
(-6012 3058);
DISPLAY 0.489362 (-6012 3058);
PAINT GREEN (-6012 3058);
FORCEPROP 2 LAST CDS_LIB mstr_standard
J 0
(-5950 3050);
DISPLAY 0.723404 (-5950 3050);
PAINT MONO (-5950 3050);
DISPLAY INVISIBLE (-5950 3050);
FORCEPROP 1 LAST BODY_TYPE PLUMBING
J 0
(-5950 3100);
DISPLAY 0.872340 (-5950 3100);
PAINT GREEN (-5950 3100);
DISPLAY INVISIBLE (-5950 3100);
FORCEPROP 1 LAST HDL_TAP TRUE
J 0
(-5625 2925);
DISPLAY 0.872340 (-5625 2925);
DISPLAY INVISIBLE (-5625 2925);
FORCEPROP 1 LAST PATH I53
J 0
(-5952 3050);
DISPLAY 0.872340 (-5952 3050);
PAINT GREEN (-5952 3050);
DISPLAY INVISIBLE (-5952 3050);
FORCEADD TAP..1
(-5950 3100);
FORCEPROP 3 LASTPIN (-6000 3100) SIG_NAME M_H_CPU1_SB_DQ<18>
J 0
(-5990 3110);
DISPLAY 0.659574 (-5990 3110);
PAINT MONO (-5990 3110);
DISPLAY INVISIBLE (-5990 3110);
FORCEPROP 1 LASTPIN (-6000 3100) BN 18
J 0
(-6012 3108);
DISPLAY 0.489362 (-6012 3108);
PAINT GREEN (-6012 3108);
FORCEPROP 2 LAST CDS_LIB mstr_standard
J 0
(-5950 3100);
DISPLAY 0.723404 (-5950 3100);
PAINT MONO (-5950 3100);
DISPLAY INVISIBLE (-5950 3100);
FORCEPROP 1 LAST BODY_TYPE PLUMBING
J 0
(-5950 3150);
DISPLAY 0.872340 (-5950 3150);
PAINT GREEN (-5950 3150);
DISPLAY INVISIBLE (-5950 3150);
FORCEPROP 1 LAST HDL_TAP TRUE
J 0
(-5625 2975);
DISPLAY 0.872340 (-5625 2975);
DISPLAY INVISIBLE (-5625 2975);
FORCEPROP 1 LAST PATH I54
J 0
(-5952 3100);
DISPLAY 0.872340 (-5952 3100);
PAINT GREEN (-5952 3100);
DISPLAY INVISIBLE (-5952 3100);
FORCEADD TAP..1
(-5950 3150);
FORCEPROP 3 LASTPIN (-6000 3150) SIG_NAME M_H_CPU1_SB_DQ<19>
J 0
(-5990 3160);
DISPLAY 0.659574 (-5990 3160);
PAINT MONO (-5990 3160);
DISPLAY INVISIBLE (-5990 3160);
FORCEPROP 1 LASTPIN (-6000 3150) BN 19
J 0
(-6012 3158);
DISPLAY 0.489362 (-6012 3158);
PAINT GREEN (-6012 3158);
FORCEPROP 2 LAST CDS_LIB mstr_standard
J 0
(-5950 3150);
DISPLAY 0.723404 (-5950 3150);
PAINT MONO (-5950 3150);
DISPLAY INVISIBLE (-5950 3150);
FORCEPROP 1 LAST BODY_TYPE PLUMBING
J 0
(-5950 3200);
DISPLAY 0.872340 (-5950 3200);
PAINT GREEN (-5950 3200);
DISPLAY INVISIBLE (-5950 3200);
FORCEPROP 1 LAST HDL_TAP TRUE
J 0
(-5625 3025);
DISPLAY 0.872340 (-5625 3025);
DISPLAY INVISIBLE (-5625 3025);
FORCEPROP 1 LAST PATH I55
J 0
(-5952 3150);
DISPLAY 0.872340 (-5952 3150);
PAINT GREEN (-5952 3150);
DISPLAY INVISIBLE (-5952 3150);
FORCEADD TAP..1
(-5950 3200);
FORCEPROP 3 LASTPIN (-6000 3200) SIG_NAME M_H_CPU1_SB_DQ<20>
J 0
(-5990 3210);
DISPLAY 0.659574 (-5990 3210);
PAINT MONO (-5990 3210);
DISPLAY INVISIBLE (-5990 3210);
FORCEPROP 1 LASTPIN (-6000 3200) BN 20
J 0
(-6012 3208);
DISPLAY 0.489362 (-6012 3208);
PAINT GREEN (-6012 3208);
FORCEPROP 2 LAST CDS_LIB mstr_standard
J 0
(-5950 3200);
DISPLAY 0.723404 (-5950 3200);
PAINT MONO (-5950 3200);
DISPLAY INVISIBLE (-5950 3200);
FORCEPROP 1 LAST BODY_TYPE PLUMBING
J 0
(-5950 3250);
DISPLAY 0.872340 (-5950 3250);
PAINT GREEN (-5950 3250);
DISPLAY INVISIBLE (-5950 3250);
FORCEPROP 1 LAST HDL_TAP TRUE
J 0
(-5625 3075);
DISPLAY 0.872340 (-5625 3075);
DISPLAY INVISIBLE (-5625 3075);
FORCEPROP 1 LAST PATH I56
J 0
(-5952 3200);
DISPLAY 0.872340 (-5952 3200);
PAINT GREEN (-5952 3200);
DISPLAY INVISIBLE (-5952 3200);
FORCEADD TAP..1
(-5950 3250);
FORCEPROP 3 LASTPIN (-6000 3250) SIG_NAME M_H_CPU1_SB_DQ<21>
J 0
(-5990 3260);
DISPLAY 0.659574 (-5990 3260);
PAINT MONO (-5990 3260);
DISPLAY INVISIBLE (-5990 3260);
FORCEPROP 1 LASTPIN (-6000 3250) BN 21
J 0
(-6012 3258);
DISPLAY 0.489362 (-6012 3258);
PAINT GREEN (-6012 3258);
FORCEPROP 2 LAST CDS_LIB mstr_standard
J 0
(-5950 3250);
DISPLAY 0.723404 (-5950 3250);
PAINT MONO (-5950 3250);
DISPLAY INVISIBLE (-5950 3250);
FORCEPROP 1 LAST BODY_TYPE PLUMBING
J 0
(-5950 3300);
DISPLAY 0.872340 (-5950 3300);
PAINT GREEN (-5950 3300);
DISPLAY INVISIBLE (-5950 3300);
FORCEPROP 1 LAST HDL_TAP TRUE
J 0
(-5625 3125);
DISPLAY 0.872340 (-5625 3125);
DISPLAY INVISIBLE (-5625 3125);
FORCEPROP 1 LAST PATH I57
J 0
(-5952 3250);
DISPLAY 0.872340 (-5952 3250);
PAINT GREEN (-5952 3250);
DISPLAY INVISIBLE (-5952 3250);
FORCEADD TAP..1
(-5950 3300);
FORCEPROP 3 LASTPIN (-6000 3300) SIG_NAME M_H_CPU1_SB_DQ<22>
J 0
(-5990 3310);
DISPLAY 0.659574 (-5990 3310);
PAINT MONO (-5990 3310);
DISPLAY INVISIBLE (-5990 3310);
FORCEPROP 1 LASTPIN (-6000 3300) BN 22
J 0
(-6012 3308);
DISPLAY 0.489362 (-6012 3308);
PAINT GREEN (-6012 3308);
FORCEPROP 2 LAST CDS_LIB mstr_standard
J 0
(-5950 3300);
DISPLAY 0.723404 (-5950 3300);
PAINT MONO (-5950 3300);
DISPLAY INVISIBLE (-5950 3300);
FORCEPROP 1 LAST BODY_TYPE PLUMBING
J 0
(-5950 3350);
DISPLAY 0.872340 (-5950 3350);
PAINT GREEN (-5950 3350);
DISPLAY INVISIBLE (-5950 3350);
FORCEPROP 1 LAST HDL_TAP TRUE
J 0
(-5625 3175);
DISPLAY 0.872340 (-5625 3175);
DISPLAY INVISIBLE (-5625 3175);
FORCEPROP 1 LAST PATH I58
J 0
(-5952 3300);
DISPLAY 0.872340 (-5952 3300);
PAINT GREEN (-5952 3300);
DISPLAY INVISIBLE (-5952 3300);
FORCEADD TAP..1
(-5950 3350);
FORCEPROP 3 LASTPIN (-6000 3350) SIG_NAME M_H_CPU1_SB_DQ<23>
J 0
(-5990 3360);
DISPLAY 0.659574 (-5990 3360);
PAINT MONO (-5990 3360);
DISPLAY INVISIBLE (-5990 3360);
FORCEPROP 1 LASTPIN (-6000 3350) BN 23
J 0
(-6012 3358);
DISPLAY 0.489362 (-6012 3358);
PAINT GREEN (-6012 3358);
FORCEPROP 2 LAST CDS_LIB mstr_standard
J 0
(-5950 3350);
DISPLAY 0.723404 (-5950 3350);
PAINT MONO (-5950 3350);
DISPLAY INVISIBLE (-5950 3350);
FORCEPROP 1 LAST BODY_TYPE PLUMBING
J 0
(-5950 3400);
DISPLAY 0.872340 (-5950 3400);
PAINT GREEN (-5950 3400);
DISPLAY INVISIBLE (-5950 3400);
FORCEPROP 1 LAST HDL_TAP TRUE
J 0
(-5625 3225);
DISPLAY 0.872340 (-5625 3225);
DISPLAY INVISIBLE (-5625 3225);
FORCEPROP 1 LAST PATH I59
J 0
(-5952 3350);
DISPLAY 0.872340 (-5952 3350);
PAINT GREEN (-5952 3350);
DISPLAY INVISIBLE (-5952 3350);
FORCEADD OFFPAGE..1
(-8550 2900);
FORCEPROP 2 LAST $XR0 105 
J 0
(-8802 2900);
DISPLAY 0.638298 (-8802 2900);
PAINT MONO (-8802 2900);
FORCEPROP 2 LAST CDS_LIB mstr_standard
J 0
(-8550 2900);
DISPLAY 0.808511 (-8550 2900);
DISPLAY INVISIBLE (-8550 2900);
FORCEPROP 1 LAST OFFPAGE TRUE
J 0
(-8225 2775);
DISPLAY 0.872340 (-8225 2775);
PAINT GREEN (-8225 2775);
DISPLAY INVISIBLE (-8225 2775);
FORCEPROP 1 LAST COMMENT_BODY TRUE
J 0
(-8425 2800);
DISPLAY 0.872340 (-8425 2800);
PAINT GREEN (-8425 2800);
DISPLAY INVISIBLE (-8425 2800);
FORCEPROP 2 LAST PATH I6
J 0
(-8950 2950);
DISPLAY 1.021277 (-8950 2950);
DISPLAY INVISIBLE (-8950 2950);
FORCEADD TAP..1
(-5950 3400);
FORCEPROP 3 LASTPIN (-6000 3400) SIG_NAME M_H_CPU1_SB_DQ<24>
J 0
(-5990 3410);
DISPLAY 0.659574 (-5990 3410);
PAINT MONO (-5990 3410);
DISPLAY INVISIBLE (-5990 3410);
FORCEPROP 1 LASTPIN (-6000 3400) BN 24
J 0
(-6012 3408);
DISPLAY 0.489362 (-6012 3408);
PAINT GREEN (-6012 3408);
FORCEPROP 2 LAST CDS_LIB mstr_standard
J 0
(-5950 3400);
DISPLAY 0.723404 (-5950 3400);
PAINT MONO (-5950 3400);
DISPLAY INVISIBLE (-5950 3400);
FORCEPROP 1 LAST BODY_TYPE PLUMBING
J 0
(-5950 3450);
DISPLAY 0.872340 (-5950 3450);
PAINT GREEN (-5950 3450);
DISPLAY INVISIBLE (-5950 3450);
FORCEPROP 1 LAST HDL_TAP TRUE
J 0
(-5625 3275);
DISPLAY 0.872340 (-5625 3275);
DISPLAY INVISIBLE (-5625 3275);
FORCEPROP 1 LAST PATH I60
J 0
(-5952 3400);
DISPLAY 0.872340 (-5952 3400);
PAINT GREEN (-5952 3400);
DISPLAY INVISIBLE (-5952 3400);
FORCEADD TAP..1
(-5950 3450);
FORCEPROP 3 LASTPIN (-6000 3450) SIG_NAME M_H_CPU1_SB_DQ<25>
J 0
(-5990 3460);
DISPLAY 0.659574 (-5990 3460);
PAINT MONO (-5990 3460);
DISPLAY INVISIBLE (-5990 3460);
FORCEPROP 1 LASTPIN (-6000 3450) BN 25
J 0
(-6012 3458);
DISPLAY 0.489362 (-6012 3458);
PAINT GREEN (-6012 3458);
FORCEPROP 2 LAST CDS_LIB mstr_standard
J 0
(-5950 3450);
DISPLAY 0.723404 (-5950 3450);
PAINT MONO (-5950 3450);
DISPLAY INVISIBLE (-5950 3450);
FORCEPROP 1 LAST BODY_TYPE PLUMBING
J 0
(-5950 3500);
DISPLAY 0.872340 (-5950 3500);
PAINT GREEN (-5950 3500);
DISPLAY INVISIBLE (-5950 3500);
FORCEPROP 1 LAST HDL_TAP TRUE
J 0
(-5625 3325);
DISPLAY 0.872340 (-5625 3325);
DISPLAY INVISIBLE (-5625 3325);
FORCEPROP 1 LAST PATH I61
J 0
(-5952 3450);
DISPLAY 0.872340 (-5952 3450);
PAINT GREEN (-5952 3450);
DISPLAY INVISIBLE (-5952 3450);
FORCEADD TAP..1
(-5950 3500);
FORCEPROP 3 LASTPIN (-6000 3500) SIG_NAME M_H_CPU1_SB_DQ<26>
J 0
(-5990 3510);
DISPLAY 0.659574 (-5990 3510);
PAINT MONO (-5990 3510);
DISPLAY INVISIBLE (-5990 3510);
FORCEPROP 1 LASTPIN (-6000 3500) BN 26
J 0
(-6012 3508);
DISPLAY 0.489362 (-6012 3508);
PAINT GREEN (-6012 3508);
FORCEPROP 2 LAST CDS_LIB mstr_standard
J 0
(-5950 3500);
DISPLAY 0.723404 (-5950 3500);
PAINT MONO (-5950 3500);
DISPLAY INVISIBLE (-5950 3500);
FORCEPROP 1 LAST BODY_TYPE PLUMBING
J 0
(-5950 3550);
DISPLAY 0.872340 (-5950 3550);
PAINT GREEN (-5950 3550);
DISPLAY INVISIBLE (-5950 3550);
FORCEPROP 1 LAST HDL_TAP TRUE
J 0
(-5625 3375);
DISPLAY 0.872340 (-5625 3375);
DISPLAY INVISIBLE (-5625 3375);
FORCEPROP 1 LAST PATH I62
J 0
(-5952 3500);
DISPLAY 0.872340 (-5952 3500);
PAINT GREEN (-5952 3500);
DISPLAY INVISIBLE (-5952 3500);
FORCEADD TAP..1
(-5950 3550);
FORCEPROP 3 LASTPIN (-6000 3550) SIG_NAME M_H_CPU1_SB_DQ<27>
J 0
(-5990 3560);
DISPLAY 0.659574 (-5990 3560);
PAINT MONO (-5990 3560);
DISPLAY INVISIBLE (-5990 3560);
FORCEPROP 1 LASTPIN (-6000 3550) BN 27
J 0
(-6012 3558);
DISPLAY 0.489362 (-6012 3558);
PAINT GREEN (-6012 3558);
FORCEPROP 2 LAST CDS_LIB mstr_standard
J 0
(-5950 3550);
DISPLAY 0.723404 (-5950 3550);
PAINT MONO (-5950 3550);
DISPLAY INVISIBLE (-5950 3550);
FORCEPROP 1 LAST BODY_TYPE PLUMBING
J 0
(-5950 3600);
DISPLAY 0.872340 (-5950 3600);
PAINT GREEN (-5950 3600);
DISPLAY INVISIBLE (-5950 3600);
FORCEPROP 1 LAST HDL_TAP TRUE
J 0
(-5625 3425);
DISPLAY 0.872340 (-5625 3425);
DISPLAY INVISIBLE (-5625 3425);
FORCEPROP 1 LAST PATH I63
J 0
(-5952 3550);
DISPLAY 0.872340 (-5952 3550);
PAINT GREEN (-5952 3550);
DISPLAY INVISIBLE (-5952 3550);
FORCEADD TAP..1
(-5950 3600);
FORCEPROP 3 LASTPIN (-6000 3600) SIG_NAME M_H_CPU1_SB_DQ<28>
J 0
(-5990 3610);
DISPLAY 0.659574 (-5990 3610);
PAINT MONO (-5990 3610);
DISPLAY INVISIBLE (-5990 3610);
FORCEPROP 1 LASTPIN (-6000 3600) BN 28
J 0
(-6012 3608);
DISPLAY 0.489362 (-6012 3608);
PAINT GREEN (-6012 3608);
FORCEPROP 2 LAST CDS_LIB mstr_standard
J 0
(-5950 3600);
DISPLAY 0.723404 (-5950 3600);
PAINT MONO (-5950 3600);
DISPLAY INVISIBLE (-5950 3600);
FORCEPROP 1 LAST BODY_TYPE PLUMBING
J 0
(-5950 3650);
DISPLAY 0.872340 (-5950 3650);
PAINT GREEN (-5950 3650);
DISPLAY INVISIBLE (-5950 3650);
FORCEPROP 1 LAST HDL_TAP TRUE
J 0
(-5625 3475);
DISPLAY 0.872340 (-5625 3475);
DISPLAY INVISIBLE (-5625 3475);
FORCEPROP 1 LAST PATH I64
J 0
(-5952 3600);
DISPLAY 0.872340 (-5952 3600);
PAINT GREEN (-5952 3600);
DISPLAY INVISIBLE (-5952 3600);
FORCEADD TAP..1
(-5950 3650);
FORCEPROP 3 LASTPIN (-6000 3650) SIG_NAME M_H_CPU1_SB_DQ<29>
J 0
(-5990 3660);
DISPLAY 0.659574 (-5990 3660);
PAINT MONO (-5990 3660);
DISPLAY INVISIBLE (-5990 3660);
FORCEPROP 1 LASTPIN (-6000 3650) BN 29
J 0
(-6012 3658);
DISPLAY 0.489362 (-6012 3658);
PAINT GREEN (-6012 3658);
FORCEPROP 2 LAST CDS_LIB mstr_standard
J 0
(-5950 3650);
DISPLAY 0.723404 (-5950 3650);
PAINT MONO (-5950 3650);
DISPLAY INVISIBLE (-5950 3650);
FORCEPROP 1 LAST BODY_TYPE PLUMBING
J 0
(-5950 3700);
DISPLAY 0.872340 (-5950 3700);
PAINT GREEN (-5950 3700);
DISPLAY INVISIBLE (-5950 3700);
FORCEPROP 1 LAST HDL_TAP TRUE
J 0
(-5625 3525);
DISPLAY 0.872340 (-5625 3525);
DISPLAY INVISIBLE (-5625 3525);
FORCEPROP 1 LAST PATH I65
J 0
(-5952 3650);
DISPLAY 0.872340 (-5952 3650);
PAINT GREEN (-5952 3650);
DISPLAY INVISIBLE (-5952 3650);
FORCEADD TAP..1
(-5950 3750);
FORCEPROP 3 LASTPIN (-6000 3750) SIG_NAME M_H_CPU1_SB_DQ<31>
J 0
(-5990 3760);
DISPLAY 0.659574 (-5990 3760);
PAINT MONO (-5990 3760);
DISPLAY INVISIBLE (-5990 3760);
FORCEPROP 1 LASTPIN (-6000 3750) BN 31
J 0
(-6012 3758);
DISPLAY 0.489362 (-6012 3758);
PAINT GREEN (-6012 3758);
FORCEPROP 2 LAST CDS_LIB mstr_standard
J 0
(-5950 3750);
DISPLAY 0.723404 (-5950 3750);
PAINT MONO (-5950 3750);
DISPLAY INVISIBLE (-5950 3750);
FORCEPROP 1 LAST BODY_TYPE PLUMBING
J 0
(-5950 3800);
DISPLAY 0.872340 (-5950 3800);
PAINT GREEN (-5950 3800);
DISPLAY INVISIBLE (-5950 3800);
FORCEPROP 1 LAST HDL_TAP TRUE
J 0
(-5625 3625);
DISPLAY 0.872340 (-5625 3625);
DISPLAY INVISIBLE (-5625 3625);
FORCEPROP 1 LAST PATH I66
J 0
(-5952 3750);
DISPLAY 0.872340 (-5952 3750);
PAINT GREEN (-5952 3750);
DISPLAY INVISIBLE (-5952 3750);
FORCEADD TAP..1
(-5950 3700);
FORCEPROP 3 LASTPIN (-6000 3700) SIG_NAME M_H_CPU1_SB_DQ<30>
J 0
(-5990 3710);
DISPLAY 0.659574 (-5990 3710);
PAINT MONO (-5990 3710);
DISPLAY INVISIBLE (-5990 3710);
FORCEPROP 1 LASTPIN (-6000 3700) BN 30
J 0
(-6012 3708);
DISPLAY 0.489362 (-6012 3708);
PAINT GREEN (-6012 3708);
FORCEPROP 2 LAST CDS_LIB mstr_standard
J 0
(-5950 3700);
DISPLAY 0.723404 (-5950 3700);
PAINT MONO (-5950 3700);
DISPLAY INVISIBLE (-5950 3700);
FORCEPROP 1 LAST BODY_TYPE PLUMBING
J 0
(-5950 3750);
DISPLAY 0.872340 (-5950 3750);
PAINT GREEN (-5950 3750);
DISPLAY INVISIBLE (-5950 3750);
FORCEPROP 1 LAST HDL_TAP TRUE
J 0
(-5625 3575);
DISPLAY 0.872340 (-5625 3575);
DISPLAY INVISIBLE (-5625 3575);
FORCEPROP 1 LAST PATH I67
J 0
(-5952 3700);
DISPLAY 0.872340 (-5952 3700);
PAINT GREEN (-5952 3700);
DISPLAY INVISIBLE (-5952 3700);
FORCEADD TAP..1
(-5950 3850);
FORCEPROP 3 LASTPIN (-6000 3850) SIG_NAME M_H_CPU1_SA_DQ<0>
J 0
(-5990 3860);
DISPLAY 0.659574 (-5990 3860);
PAINT MONO (-5990 3860);
DISPLAY INVISIBLE (-5990 3860);
FORCEPROP 1 LASTPIN (-6000 3850) BN 0
J 0
(-6012 3858);
DISPLAY 0.489362 (-6012 3858);
PAINT GREEN (-6012 3858);
FORCEPROP 2 LAST CDS_LIB mstr_standard
J 0
(-5950 3850);
DISPLAY 0.723404 (-5950 3850);
PAINT MONO (-5950 3850);
DISPLAY INVISIBLE (-5950 3850);
FORCEPROP 1 LAST BODY_TYPE PLUMBING
J 0
(-5950 3900);
DISPLAY 0.872340 (-5950 3900);
PAINT GREEN (-5950 3900);
DISPLAY INVISIBLE (-5950 3900);
FORCEPROP 1 LAST HDL_TAP TRUE
J 0
(-5625 3725);
DISPLAY 0.872340 (-5625 3725);
DISPLAY INVISIBLE (-5625 3725);
FORCEPROP 1 LAST PATH I68
J 0
(-5952 3850);
DISPLAY 0.872340 (-5952 3850);
PAINT GREEN (-5952 3850);
DISPLAY INVISIBLE (-5952 3850);
FORCEADD OFFPAGE..5
(-8100 3050);
FORCEPROP 2 LAST $XR0 44 
J 0
(-8324 3050);
DISPLAY 0.638298 (-8324 3050);
PAINT MONO (-8324 3050);
FORCEPROP 2 LAST CDS_LIB mstr_standard
J 0
(-8100 3050);
DISPLAY INVISIBLE (-8100 3050);
FORCEPROP 1 LAST OFFPAGE TRUE
J 0
(-7775 2925);
DISPLAY 0.872340 (-7775 2925);
PAINT GREEN (-7775 2925);
DISPLAY INVISIBLE (-7775 2925);
FORCEPROP 1 LAST COMMENT_BODY TRUE
J 0
(-8000 2975);
DISPLAY 0.872340 (-8000 2975);
PAINT GREEN (-8000 2975);
DISPLAY INVISIBLE (-8000 2975);
FORCEPROP 2 LAST PATH I7
J 0
(-8300 3100);
DISPLAY 1.021277 (-8300 3100);
DISPLAY INVISIBLE (-8300 3100);
FORCEADD OFFPAGE..3
(-5325 3800);
FORCEPROP 2 LAST $XR0 44 
J 0
(-5111 3800);
DISPLAY 0.638298 (-5111 3800);
PAINT MONO (-5111 3800);
FORCEPROP 2 LAST CDS_LIB mstr_standard
J 0
(-5325 3800);
DISPLAY 0.723404 (-5325 3800);
PAINT MONO (-5325 3800);
DISPLAY INVISIBLE (-5325 3800);
FORCEPROP 1 LAST OFFPAGE TRUE
J 0
(-5000 3675);
DISPLAY 0.872340 (-5000 3675);
PAINT GREEN (-5000 3675);
DISPLAY INVISIBLE (-5000 3675);
FORCEPROP 1 LAST COMMENT_BODY TRUE
J 0
(-5375 3700);
DISPLAY 0.872340 (-5375 3700);
PAINT GREEN (-5375 3700);
DISPLAY INVISIBLE (-5375 3700);
FORCEPROP 2 LAST PATH I76
J 0
(-5100 3850);
DISPLAY 1.021277 (-5100 3850);
DISPLAY INVISIBLE (-5100 3850);
FORCEADD TAP..1
R 2
(-7650 4000);
FORCEPROP 3 LASTPIN (-7600 4000) SIG_NAME M_H_CPU1_SA_CB<7>
J 0
(-7590 4010);
DISPLAY 0.659574 (-7590 4010);
PAINT MONO (-7590 4010);
DISPLAY INVISIBLE (-7590 4010);
FORCEPROP 1 LASTPIN (-7600 4000) BN 7
J 2
(-7588 4008);
DISPLAY 0.489362 (-7588 4008);
PAINT GREEN (-7588 4008);
FORCEPROP 2 LAST CDS_LIB mstr_standard
J 0
(-7650 4000);
DISPLAY 0.723404 (-7650 4000);
PAINT MONO (-7650 4000);
DISPLAY INVISIBLE (-7650 4000);
FORCEPROP 1 LAST BODY_TYPE PLUMBING
J 2
(-7650 4050);
DISPLAY 0.872340 (-7650 4050);
PAINT GREEN (-7650 4050);
DISPLAY INVISIBLE (-7650 4050);
FORCEPROP 1 LAST HDL_TAP TRUE
J 2
(-7975 3875);
DISPLAY 0.872340 (-7975 3875);
DISPLAY INVISIBLE (-7975 3875);
FORCEPROP 1 LAST PATH I77
J 2
(-7648 4000);
DISPLAY 0.872340 (-7648 4000);
PAINT GREEN (-7648 4000);
DISPLAY INVISIBLE (-7648 4000);
FORCEADD TAP..1
R 2
(-7650 3950);
FORCEPROP 3 LASTPIN (-7600 3950) SIG_NAME M_H_CPU1_SA_CB<6>
J 0
(-7590 3960);
DISPLAY 0.659574 (-7590 3960);
PAINT MONO (-7590 3960);
DISPLAY INVISIBLE (-7590 3960);
FORCEPROP 1 LASTPIN (-7600 3950) BN 6
J 2
(-7588 3958);
DISPLAY 0.489362 (-7588 3958);
PAINT GREEN (-7588 3958);
FORCEPROP 2 LAST CDS_LIB mstr_standard
J 0
(-7650 3950);
DISPLAY 0.723404 (-7650 3950);
PAINT MONO (-7650 3950);
DISPLAY INVISIBLE (-7650 3950);
FORCEPROP 1 LAST BODY_TYPE PLUMBING
J 2
(-7650 4000);
DISPLAY 0.872340 (-7650 4000);
PAINT GREEN (-7650 4000);
DISPLAY INVISIBLE (-7650 4000);
FORCEPROP 1 LAST HDL_TAP TRUE
J 2
(-7975 3825);
DISPLAY 0.872340 (-7975 3825);
DISPLAY INVISIBLE (-7975 3825);
FORCEPROP 1 LAST PATH I78
J 2
(-7648 3950);
DISPLAY 0.872340 (-7648 3950);
PAINT GREEN (-7648 3950);
DISPLAY INVISIBLE (-7648 3950);
FORCEADD TAP..1
R 2
(-7650 3900);
FORCEPROP 3 LASTPIN (-7600 3900) SIG_NAME M_H_CPU1_SA_CB<5>
J 0
(-7590 3910);
DISPLAY 0.659574 (-7590 3910);
PAINT MONO (-7590 3910);
DISPLAY INVISIBLE (-7590 3910);
FORCEPROP 1 LASTPIN (-7600 3900) BN 5
J 2
(-7588 3908);
DISPLAY 0.489362 (-7588 3908);
PAINT GREEN (-7588 3908);
FORCEPROP 2 LAST CDS_LIB mstr_standard
J 0
(-7650 3900);
DISPLAY 0.723404 (-7650 3900);
PAINT MONO (-7650 3900);
DISPLAY INVISIBLE (-7650 3900);
FORCEPROP 1 LAST BODY_TYPE PLUMBING
J 2
(-7650 3950);
DISPLAY 0.872340 (-7650 3950);
PAINT GREEN (-7650 3950);
DISPLAY INVISIBLE (-7650 3950);
FORCEPROP 1 LAST HDL_TAP TRUE
J 2
(-7975 3775);
DISPLAY 0.872340 (-7975 3775);
DISPLAY INVISIBLE (-7975 3775);
FORCEPROP 1 LAST PATH I79
J 2
(-7648 3900);
DISPLAY 0.872340 (-7648 3900);
PAINT GREEN (-7648 3900);
DISPLAY INVISIBLE (-7648 3900);
FORCEADD OFFPAGE..1
(-8100 3100);
FORCEPROP 2 LAST $XR0 44 
J 0
(-8321 3100);
DISPLAY 0.638298 (-8321 3100);
PAINT MONO (-8321 3100);
FORCEPROP 2 LAST CDS_LIB mstr_standard
J 0
(-8100 3100);
DISPLAY 0.808511 (-8100 3100);
DISPLAY INVISIBLE (-8100 3100);
FORCEPROP 1 LAST OFFPAGE TRUE
J 0
(-7775 2975);
DISPLAY 0.872340 (-7775 2975);
PAINT GREEN (-7775 2975);
DISPLAY INVISIBLE (-7775 2975);
FORCEPROP 1 LAST COMMENT_BODY TRUE
J 0
(-7975 3000);
DISPLAY 0.872340 (-7975 3000);
PAINT GREEN (-7975 3000);
DISPLAY INVISIBLE (-7975 3000);
FORCEPROP 2 LAST PATH I8
J 0
(-8300 3150);
DISPLAY 1.021277 (-8300 3150);
DISPLAY INVISIBLE (-8300 3150);
FORCEADD TAP..1
R 2
(-7650 4850);
FORCEPROP 3 LASTPIN (-7600 4850) SIG_NAME M_H_CPU1_SB_CA<3>
J 0
(-7590 4860);
DISPLAY 0.659574 (-7590 4860);
PAINT MONO (-7590 4860);
DISPLAY INVISIBLE (-7590 4860);
FORCEPROP 1 LASTPIN (-7600 4850) BN 3
J 2
(-7588 4858);
DISPLAY 0.489362 (-7588 4858);
PAINT GREEN (-7588 4858);
FORCEPROP 2 LAST CDS_LIB mstr_standard
J 0
(-7650 4850);
DISPLAY 0.723404 (-7650 4850);
PAINT MONO (-7650 4850);
DISPLAY INVISIBLE (-7650 4850);
FORCEPROP 1 LAST BODY_TYPE PLUMBING
J 2
(-7650 4900);
DISPLAY 0.872340 (-7650 4900);
PAINT GREEN (-7650 4900);
DISPLAY INVISIBLE (-7650 4900);
FORCEPROP 1 LAST HDL_TAP TRUE
J 2
(-7975 4725);
DISPLAY 0.872340 (-7975 4725);
DISPLAY INVISIBLE (-7975 4725);
FORCEPROP 1 LAST PATH I80
J 2
(-7648 4850);
DISPLAY 0.872340 (-7648 4850);
PAINT GREEN (-7648 4850);
DISPLAY INVISIBLE (-7648 4850);
FORCEADD TAP..1
R 2
(-7650 4800);
FORCEPROP 3 LASTPIN (-7600 4800) SIG_NAME M_H_CPU1_SB_CA<2>
J 0
(-7590 4810);
DISPLAY 0.659574 (-7590 4810);
PAINT MONO (-7590 4810);
DISPLAY INVISIBLE (-7590 4810);
FORCEPROP 1 LASTPIN (-7600 4800) BN 2
J 2
(-7588 4808);
DISPLAY 0.489362 (-7588 4808);
PAINT GREEN (-7588 4808);
FORCEPROP 2 LAST CDS_LIB mstr_standard
J 0
(-7650 4800);
DISPLAY 0.723404 (-7650 4800);
PAINT MONO (-7650 4800);
DISPLAY INVISIBLE (-7650 4800);
FORCEPROP 1 LAST BODY_TYPE PLUMBING
J 2
(-7650 4850);
DISPLAY 0.872340 (-7650 4850);
PAINT GREEN (-7650 4850);
DISPLAY INVISIBLE (-7650 4850);
FORCEPROP 1 LAST HDL_TAP TRUE
J 2
(-7975 4675);
DISPLAY 0.872340 (-7975 4675);
DISPLAY INVISIBLE (-7975 4675);
FORCEPROP 1 LAST PATH I81
J 2
(-7648 4800);
DISPLAY 0.872340 (-7648 4800);
PAINT GREEN (-7648 4800);
DISPLAY INVISIBLE (-7648 4800);
FORCEADD TAP..1
R 2
(-7650 4750);
FORCEPROP 3 LASTPIN (-7600 4750) SIG_NAME M_H_CPU1_SB_CA<1>
J 0
(-7590 4760);
DISPLAY 0.659574 (-7590 4760);
PAINT MONO (-7590 4760);
DISPLAY INVISIBLE (-7590 4760);
FORCEPROP 1 LASTPIN (-7600 4750) BN 1
J 2
(-7588 4758);
DISPLAY 0.489362 (-7588 4758);
PAINT GREEN (-7588 4758);
FORCEPROP 2 LAST CDS_LIB mstr_standard
J 0
(-7650 4750);
DISPLAY 0.723404 (-7650 4750);
PAINT MONO (-7650 4750);
DISPLAY INVISIBLE (-7650 4750);
FORCEPROP 1 LAST BODY_TYPE PLUMBING
J 2
(-7650 4800);
DISPLAY 0.872340 (-7650 4800);
PAINT GREEN (-7650 4800);
DISPLAY INVISIBLE (-7650 4800);
FORCEPROP 1 LAST HDL_TAP TRUE
J 2
(-7975 4625);
DISPLAY 0.872340 (-7975 4625);
DISPLAY INVISIBLE (-7975 4625);
FORCEPROP 1 LAST PATH I82
J 2
(-7648 4750);
DISPLAY 0.872340 (-7648 4750);
PAINT GREEN (-7648 4750);
DISPLAY INVISIBLE (-7648 4750);
FORCEADD TAP..1
R 2
(-7650 4700);
FORCEPROP 3 LASTPIN (-7600 4700) SIG_NAME M_H_CPU1_SB_CA<0>
J 0
(-7590 4710);
DISPLAY 0.659574 (-7590 4710);
PAINT MONO (-7590 4710);
DISPLAY INVISIBLE (-7590 4710);
FORCEPROP 1 LASTPIN (-7600 4700) BN 0
J 2
(-7588 4708);
DISPLAY 0.489362 (-7588 4708);
PAINT GREEN (-7588 4708);
FORCEPROP 2 LAST CDS_LIB mstr_standard
J 0
(-7650 4700);
DISPLAY 0.723404 (-7650 4700);
PAINT MONO (-7650 4700);
DISPLAY INVISIBLE (-7650 4700);
FORCEPROP 1 LAST BODY_TYPE PLUMBING
J 2
(-7650 4750);
DISPLAY 0.872340 (-7650 4750);
PAINT GREEN (-7650 4750);
DISPLAY INVISIBLE (-7650 4750);
FORCEPROP 1 LAST HDL_TAP TRUE
J 2
(-7975 4575);
DISPLAY 0.872340 (-7975 4575);
DISPLAY INVISIBLE (-7975 4575);
FORCEPROP 1 LAST PATH I83
J 2
(-7648 4700);
DISPLAY 0.872340 (-7648 4700);
PAINT GREEN (-7648 4700);
DISPLAY INVISIBLE (-7648 4700);
FORCEADD TAP..1
R 2
(-7650 4900);
FORCEPROP 3 LASTPIN (-7600 4900) SIG_NAME M_H_CPU1_SB_CA<4>
J 0
(-7590 4910);
DISPLAY 0.659574 (-7590 4910);
PAINT MONO (-7590 4910);
DISPLAY INVISIBLE (-7590 4910);
FORCEPROP 1 LASTPIN (-7600 4900) BN 4
J 2
(-7588 4908);
DISPLAY 0.489362 (-7588 4908);
PAINT GREEN (-7588 4908);
FORCEPROP 2 LAST CDS_LIB mstr_standard
J 0
(-7650 4900);
DISPLAY 0.723404 (-7650 4900);
PAINT MONO (-7650 4900);
DISPLAY INVISIBLE (-7650 4900);
FORCEPROP 1 LAST BODY_TYPE PLUMBING
J 2
(-7650 4950);
DISPLAY 0.872340 (-7650 4950);
PAINT GREEN (-7650 4950);
DISPLAY INVISIBLE (-7650 4950);
FORCEPROP 1 LAST HDL_TAP TRUE
J 2
(-7975 4775);
DISPLAY 0.872340 (-7975 4775);
DISPLAY INVISIBLE (-7975 4775);
FORCEPROP 1 LAST PATH I84
J 2
(-7648 4900);
DISPLAY 0.872340 (-7648 4900);
PAINT GREEN (-7648 4900);
DISPLAY INVISIBLE (-7648 4900);
FORCEADD TAP..1
R 2
(-7650 4950);
FORCEPROP 3 LASTPIN (-7600 4950) SIG_NAME M_H_CPU1_SB_CA<5>
J 0
(-7590 4960);
DISPLAY 0.659574 (-7590 4960);
PAINT MONO (-7590 4960);
DISPLAY INVISIBLE (-7590 4960);
FORCEPROP 1 LASTPIN (-7600 4950) BN 5
J 2
(-7588 4958);
DISPLAY 0.489362 (-7588 4958);
PAINT GREEN (-7588 4958);
FORCEPROP 2 LAST CDS_LIB mstr_standard
J 0
(-7650 4950);
DISPLAY 0.723404 (-7650 4950);
PAINT MONO (-7650 4950);
DISPLAY INVISIBLE (-7650 4950);
FORCEPROP 1 LAST BODY_TYPE PLUMBING
J 2
(-7650 5000);
DISPLAY 0.872340 (-7650 5000);
PAINT GREEN (-7650 5000);
DISPLAY INVISIBLE (-7650 5000);
FORCEPROP 1 LAST HDL_TAP TRUE
J 2
(-7975 4825);
DISPLAY 0.872340 (-7975 4825);
DISPLAY INVISIBLE (-7975 4825);
FORCEPROP 1 LAST PATH I85
J 2
(-7648 4950);
DISPLAY 0.872340 (-7648 4950);
PAINT GREEN (-7648 4950);
DISPLAY INVISIBLE (-7648 4950);
FORCEADD TAP..1
R 2
(-7650 5000);
FORCEPROP 3 LASTPIN (-7600 5000) SIG_NAME M_H_CPU1_SB_CA<6>
J 0
(-7590 5010);
DISPLAY 0.659574 (-7590 5010);
PAINT MONO (-7590 5010);
DISPLAY INVISIBLE (-7590 5010);
FORCEPROP 1 LASTPIN (-7600 5000) BN 6
J 2
(-7588 5008);
DISPLAY 0.489362 (-7588 5008);
PAINT GREEN (-7588 5008);
FORCEPROP 2 LAST CDS_LIB mstr_standard
J 0
(-7650 5000);
DISPLAY 0.723404 (-7650 5000);
PAINT MONO (-7650 5000);
DISPLAY INVISIBLE (-7650 5000);
FORCEPROP 1 LAST BODY_TYPE PLUMBING
J 2
(-7650 5050);
DISPLAY 0.872340 (-7650 5050);
PAINT GREEN (-7650 5050);
DISPLAY INVISIBLE (-7650 5050);
FORCEPROP 1 LAST HDL_TAP TRUE
J 2
(-7975 4875);
DISPLAY 0.872340 (-7975 4875);
DISPLAY INVISIBLE (-7975 4875);
FORCEPROP 1 LAST PATH I86
J 2
(-7648 5000);
DISPLAY 0.872340 (-7648 5000);
PAINT GREEN (-7648 5000);
DISPLAY INVISIBLE (-7648 5000);
FORCEADD TAP..1
R 2
(-7650 5150);
FORCEPROP 3 LASTPIN (-7600 5150) SIG_NAME M_H_CPU1_SA_CA<1>
J 0
(-7590 5160);
DISPLAY 0.659574 (-7590 5160);
PAINT MONO (-7590 5160);
DISPLAY INVISIBLE (-7590 5160);
FORCEPROP 1 LASTPIN (-7600 5150) BN 1
J 2
(-7588 5158);
DISPLAY 0.489362 (-7588 5158);
PAINT GREEN (-7588 5158);
FORCEPROP 2 LAST CDS_LIB mstr_standard
J 0
(-7650 5150);
DISPLAY 0.723404 (-7650 5150);
PAINT MONO (-7650 5150);
DISPLAY INVISIBLE (-7650 5150);
FORCEPROP 1 LAST BODY_TYPE PLUMBING
J 2
(-7650 5200);
DISPLAY 0.872340 (-7650 5200);
PAINT GREEN (-7650 5200);
DISPLAY INVISIBLE (-7650 5200);
FORCEPROP 1 LAST HDL_TAP TRUE
J 2
(-7975 5025);
DISPLAY 0.872340 (-7975 5025);
DISPLAY INVISIBLE (-7975 5025);
FORCEPROP 1 LAST PATH I87
J 2
(-7648 5150);
DISPLAY 0.872340 (-7648 5150);
PAINT GREEN (-7648 5150);
DISPLAY INVISIBLE (-7648 5150);
FORCEADD TAP..1
R 2
(-7650 5100);
FORCEPROP 3 LASTPIN (-7600 5100) SIG_NAME M_H_CPU1_SA_CA<0>
J 0
(-7590 5110);
DISPLAY 0.659574 (-7590 5110);
PAINT MONO (-7590 5110);
DISPLAY INVISIBLE (-7590 5110);
FORCEPROP 1 LASTPIN (-7600 5100) BN 0
J 2
(-7588 5108);
DISPLAY 0.489362 (-7588 5108);
PAINT GREEN (-7588 5108);
FORCEPROP 2 LAST CDS_LIB mstr_standard
J 0
(-7650 5100);
DISPLAY 0.723404 (-7650 5100);
PAINT MONO (-7650 5100);
DISPLAY INVISIBLE (-7650 5100);
FORCEPROP 1 LAST BODY_TYPE PLUMBING
J 2
(-7650 5150);
DISPLAY 0.872340 (-7650 5150);
PAINT GREEN (-7650 5150);
DISPLAY INVISIBLE (-7650 5150);
FORCEPROP 1 LAST HDL_TAP TRUE
J 2
(-7975 4975);
DISPLAY 0.872340 (-7975 4975);
DISPLAY INVISIBLE (-7975 4975);
FORCEPROP 1 LAST PATH I88
J 2
(-7648 5100);
DISPLAY 0.872340 (-7648 5100);
PAINT GREEN (-7648 5100);
DISPLAY INVISIBLE (-7648 5100);
FORCEADD TAP..1
R 2
(-7650 5200);
FORCEPROP 3 LASTPIN (-7600 5200) SIG_NAME M_H_CPU1_SA_CA<2>
J 0
(-7590 5210);
DISPLAY 0.659574 (-7590 5210);
PAINT MONO (-7590 5210);
DISPLAY INVISIBLE (-7590 5210);
FORCEPROP 1 LASTPIN (-7600 5200) BN 2
J 2
(-7588 5208);
DISPLAY 0.489362 (-7588 5208);
PAINT GREEN (-7588 5208);
FORCEPROP 2 LAST CDS_LIB mstr_standard
J 0
(-7650 5200);
DISPLAY 0.723404 (-7650 5200);
PAINT MONO (-7650 5200);
DISPLAY INVISIBLE (-7650 5200);
FORCEPROP 1 LAST BODY_TYPE PLUMBING
J 2
(-7650 5250);
DISPLAY 0.872340 (-7650 5250);
PAINT GREEN (-7650 5250);
DISPLAY INVISIBLE (-7650 5250);
FORCEPROP 1 LAST HDL_TAP TRUE
J 2
(-7975 5075);
DISPLAY 0.872340 (-7975 5075);
DISPLAY INVISIBLE (-7975 5075);
FORCEPROP 1 LAST PATH I89
J 2
(-7648 5200);
DISPLAY 0.872340 (-7648 5200);
PAINT GREEN (-7648 5200);
DISPLAY INVISIBLE (-7648 5200);
FORCEADD VCC_CORE..1
(-8475 3425);
FORCEPROP 3 LASTPIN (-8475 3375) SIG_NAME P3V3_AUX\g
J 0
(-8465 3385);
DISPLAY 0.659574 (-8465 3385);
PAINT MONO (-8465 3385);
DISPLAY INVISIBLE (-8465 3385);
FORCEPROP 1 LAST HDL_POWER P3V3_AUX
J 1
(-8475 3475);
DISPLAY 0.489362 (-8475 3475);
PAINT GREEN (-8475 3475);
FORCEPROP 2 LAST CDS_LIB mstr_symbols
J 0
(-8475 3425);
PAINT MONO (-8475 3425);
DISPLAY INVISIBLE (-8475 3425);
FORCEPROP 0 LAST VOLTAGE 3.3
J 0
(-8750 3575);
DISPLAY 1.021277 (-8750 3575);
PAINT SKYBLUE (-8750 3575);
DISPLAY INVISIBLE (-8750 3575);
FORCEPROP 2 LAST ROOM PVCCINFAON_CPU1_CTRL
J 0
(-8475 3525);
DISPLAY 0.808511 (-8475 3525);
PAINT RED (-8475 3525);
DISPLAY INVISIBLE (-8475 3525);
FORCEPROP 1 LAST PATH I9
J 0
(-8425 3450);
DISPLAY 0.872340 (-8425 3450);
PAINT AQUA (-8425 3450);
DISPLAY INVISIBLE (-8425 3450);
FORCEADD TAP..1
R 2
(-7650 5250);
FORCEPROP 3 LASTPIN (-7600 5250) SIG_NAME M_H_CPU1_SA_CA<3>
J 0
(-7590 5260);
DISPLAY 0.659574 (-7590 5260);
PAINT MONO (-7590 5260);
DISPLAY INVISIBLE (-7590 5260);
FORCEPROP 1 LASTPIN (-7600 5250) BN 3
J 2
(-7588 5258);
DISPLAY 0.489362 (-7588 5258);
PAINT GREEN (-7588 5258);
FORCEPROP 2 LAST CDS_LIB mstr_standard
J 0
(-7650 5250);
DISPLAY 0.723404 (-7650 5250);
PAINT MONO (-7650 5250);
DISPLAY INVISIBLE (-7650 5250);
FORCEPROP 1 LAST BODY_TYPE PLUMBING
J 2
(-7650 5300);
DISPLAY 0.872340 (-7650 5300);
PAINT GREEN (-7650 5300);
DISPLAY INVISIBLE (-7650 5300);
FORCEPROP 1 LAST HDL_TAP TRUE
J 2
(-7975 5125);
DISPLAY 0.872340 (-7975 5125);
DISPLAY INVISIBLE (-7975 5125);
FORCEPROP 1 LAST PATH I90
J 2
(-7648 5250);
DISPLAY 0.872340 (-7648 5250);
PAINT GREEN (-7648 5250);
DISPLAY INVISIBLE (-7648 5250);
FORCEADD TAP..1
R 2
(-7650 5300);
FORCEPROP 3 LASTPIN (-7600 5300) SIG_NAME M_H_CPU1_SA_CA<4>
J 0
(-7590 5310);
DISPLAY 0.659574 (-7590 5310);
PAINT MONO (-7590 5310);
DISPLAY INVISIBLE (-7590 5310);
FORCEPROP 1 LASTPIN (-7600 5300) BN 4
J 2
(-7588 5308);
DISPLAY 0.489362 (-7588 5308);
PAINT GREEN (-7588 5308);
FORCEPROP 2 LAST CDS_LIB mstr_standard
J 0
(-7650 5300);
DISPLAY 0.723404 (-7650 5300);
PAINT MONO (-7650 5300);
DISPLAY INVISIBLE (-7650 5300);
FORCEPROP 1 LAST BODY_TYPE PLUMBING
J 2
(-7650 5350);
DISPLAY 0.872340 (-7650 5350);
PAINT GREEN (-7650 5350);
DISPLAY INVISIBLE (-7650 5350);
FORCEPROP 1 LAST HDL_TAP TRUE
J 2
(-7975 5175);
DISPLAY 0.872340 (-7975 5175);
DISPLAY INVISIBLE (-7975 5175);
FORCEPROP 1 LAST PATH I91
J 2
(-7648 5300);
DISPLAY 0.872340 (-7648 5300);
PAINT GREEN (-7648 5300);
DISPLAY INVISIBLE (-7648 5300);
FORCEADD TAP..1
R 2
(-7650 5400);
FORCEPROP 3 LASTPIN (-7600 5400) SIG_NAME M_H_CPU1_SA_CA<6>
J 0
(-7590 5410);
DISPLAY 0.659574 (-7590 5410);
PAINT MONO (-7590 5410);
DISPLAY INVISIBLE (-7590 5410);
FORCEPROP 1 LASTPIN (-7600 5400) BN 6
J 2
(-7588 5408);
DISPLAY 0.489362 (-7588 5408);
PAINT GREEN (-7588 5408);
FORCEPROP 2 LAST CDS_LIB mstr_standard
J 0
(-7650 5400);
DISPLAY 0.723404 (-7650 5400);
PAINT MONO (-7650 5400);
DISPLAY INVISIBLE (-7650 5400);
FORCEPROP 1 LAST BODY_TYPE PLUMBING
J 2
(-7650 5450);
DISPLAY 0.872340 (-7650 5450);
PAINT GREEN (-7650 5450);
DISPLAY INVISIBLE (-7650 5450);
FORCEPROP 1 LAST HDL_TAP TRUE
J 2
(-7975 5275);
DISPLAY 0.872340 (-7975 5275);
DISPLAY INVISIBLE (-7975 5275);
FORCEPROP 1 LAST PATH I92
J 2
(-7648 5400);
DISPLAY 0.872340 (-7648 5400);
PAINT GREEN (-7648 5400);
DISPLAY INVISIBLE (-7648 5400);
FORCEADD TAP..1
R 2
(-7650 5350);
FORCEPROP 3 LASTPIN (-7600 5350) SIG_NAME M_H_CPU1_SA_CA<5>
J 0
(-7590 5360);
DISPLAY 0.659574 (-7590 5360);
PAINT MONO (-7590 5360);
DISPLAY INVISIBLE (-7590 5360);
FORCEPROP 1 LASTPIN (-7600 5350) BN 5
J 2
(-7588 5358);
DISPLAY 0.489362 (-7588 5358);
PAINT GREEN (-7588 5358);
FORCEPROP 2 LAST CDS_LIB mstr_standard
J 0
(-7650 5350);
DISPLAY 0.723404 (-7650 5350);
PAINT MONO (-7650 5350);
DISPLAY INVISIBLE (-7650 5350);
FORCEPROP 1 LAST BODY_TYPE PLUMBING
J 2
(-7650 5400);
DISPLAY 0.872340 (-7650 5400);
PAINT GREEN (-7650 5400);
DISPLAY INVISIBLE (-7650 5400);
FORCEPROP 1 LAST HDL_TAP TRUE
J 2
(-7975 5225);
DISPLAY 0.872340 (-7975 5225);
DISPLAY INVISIBLE (-7975 5225);
FORCEPROP 1 LAST PATH I93
J 2
(-7648 5350);
DISPLAY 0.872340 (-7648 5350);
PAINT GREEN (-7648 5350);
DISPLAY INVISIBLE (-7648 5350);
FORCEADD TAP..1
(-5950 3900);
FORCEPROP 3 LASTPIN (-6000 3900) SIG_NAME M_H_CPU1_SA_DQ<1>
J 0
(-5990 3910);
DISPLAY 0.659574 (-5990 3910);
PAINT MONO (-5990 3910);
DISPLAY INVISIBLE (-5990 3910);
FORCEPROP 1 LASTPIN (-6000 3900) BN 1
J 0
(-6012 3908);
DISPLAY 0.489362 (-6012 3908);
PAINT GREEN (-6012 3908);
FORCEPROP 2 LAST CDS_LIB mstr_standard
J 0
(-5950 3900);
DISPLAY 0.723404 (-5950 3900);
PAINT MONO (-5950 3900);
DISPLAY INVISIBLE (-5950 3900);
FORCEPROP 1 LAST BODY_TYPE PLUMBING
J 0
(-5950 3950);
DISPLAY 0.872340 (-5950 3950);
PAINT GREEN (-5950 3950);
DISPLAY INVISIBLE (-5950 3950);
FORCEPROP 1 LAST HDL_TAP TRUE
J 0
(-5625 3775);
DISPLAY 0.872340 (-5625 3775);
DISPLAY INVISIBLE (-5625 3775);
FORCEPROP 1 LAST PATH I94
J 0
(-5952 3900);
DISPLAY 0.872340 (-5952 3900);
PAINT GREEN (-5952 3900);
DISPLAY INVISIBLE (-5952 3900);
FORCEADD TAP..1
(-5950 3950);
FORCEPROP 3 LASTPIN (-6000 3950) SIG_NAME M_H_CPU1_SA_DQ<2>
J 0
(-5990 3960);
DISPLAY 0.659574 (-5990 3960);
PAINT MONO (-5990 3960);
DISPLAY INVISIBLE (-5990 3960);
FORCEPROP 1 LASTPIN (-6000 3950) BN 2
J 0
(-6012 3958);
DISPLAY 0.489362 (-6012 3958);
PAINT GREEN (-6012 3958);
FORCEPROP 2 LAST CDS_LIB mstr_standard
J 0
(-5950 3950);
DISPLAY 0.723404 (-5950 3950);
PAINT MONO (-5950 3950);
DISPLAY INVISIBLE (-5950 3950);
FORCEPROP 1 LAST BODY_TYPE PLUMBING
J 0
(-5950 4000);
DISPLAY 0.872340 (-5950 4000);
PAINT GREEN (-5950 4000);
DISPLAY INVISIBLE (-5950 4000);
FORCEPROP 1 LAST HDL_TAP TRUE
J 0
(-5625 3825);
DISPLAY 0.872340 (-5625 3825);
DISPLAY INVISIBLE (-5625 3825);
FORCEPROP 1 LAST PATH I95
J 0
(-5952 3950);
DISPLAY 0.872340 (-5952 3950);
PAINT GREEN (-5952 3950);
DISPLAY INVISIBLE (-5952 3950);
FORCEADD TAP..1
(-5950 4000);
FORCEPROP 3 LASTPIN (-6000 4000) SIG_NAME M_H_CPU1_SA_DQ<3>
J 0
(-5990 4010);
DISPLAY 0.659574 (-5990 4010);
PAINT MONO (-5990 4010);
DISPLAY INVISIBLE (-5990 4010);
FORCEPROP 1 LASTPIN (-6000 4000) BN 3
J 0
(-6012 4008);
DISPLAY 0.489362 (-6012 4008);
PAINT GREEN (-6012 4008);
FORCEPROP 2 LAST CDS_LIB mstr_standard
J 0
(-5950 4000);
DISPLAY 0.723404 (-5950 4000);
PAINT MONO (-5950 4000);
DISPLAY INVISIBLE (-5950 4000);
FORCEPROP 1 LAST BODY_TYPE PLUMBING
J 0
(-5950 4050);
DISPLAY 0.872340 (-5950 4050);
PAINT GREEN (-5950 4050);
DISPLAY INVISIBLE (-5950 4050);
FORCEPROP 1 LAST HDL_TAP TRUE
J 0
(-5625 3875);
DISPLAY 0.872340 (-5625 3875);
DISPLAY INVISIBLE (-5625 3875);
FORCEPROP 1 LAST PATH I96
J 0
(-5952 4000);
DISPLAY 0.872340 (-5952 4000);
PAINT GREEN (-5952 4000);
DISPLAY INVISIBLE (-5952 4000);
FORCEADD TAP..1
(-5950 4150);
FORCEPROP 3 LASTPIN (-6000 4150) SIG_NAME M_H_CPU1_SA_DQ<6>
J 0
(-5990 4160);
DISPLAY 0.659574 (-5990 4160);
PAINT MONO (-5990 4160);
DISPLAY INVISIBLE (-5990 4160);
FORCEPROP 1 LASTPIN (-6000 4150) BN 6
J 0
(-6012 4158);
DISPLAY 0.489362 (-6012 4158);
PAINT GREEN (-6012 4158);
FORCEPROP 2 LAST CDS_LIB mstr_standard
J 0
(-5950 4150);
DISPLAY 0.723404 (-5950 4150);
PAINT MONO (-5950 4150);
DISPLAY INVISIBLE (-5950 4150);
FORCEPROP 1 LAST BODY_TYPE PLUMBING
J 0
(-5950 4200);
DISPLAY 0.872340 (-5950 4200);
PAINT GREEN (-5950 4200);
DISPLAY INVISIBLE (-5950 4200);
FORCEPROP 1 LAST HDL_TAP TRUE
J 0
(-5625 4025);
DISPLAY 0.872340 (-5625 4025);
DISPLAY INVISIBLE (-5625 4025);
FORCEPROP 1 LAST PATH I97
J 0
(-5952 4150);
DISPLAY 0.872340 (-5952 4150);
PAINT GREEN (-5952 4150);
DISPLAY INVISIBLE (-5952 4150);
FORCEADD TAP..1
(-5950 4050);
FORCEPROP 3 LASTPIN (-6000 4050) SIG_NAME M_H_CPU1_SA_DQ<4>
J 0
(-5990 4060);
DISPLAY 0.659574 (-5990 4060);
PAINT MONO (-5990 4060);
DISPLAY INVISIBLE (-5990 4060);
FORCEPROP 1 LASTPIN (-6000 4050) BN 4
J 0
(-6012 4058);
DISPLAY 0.489362 (-6012 4058);
PAINT GREEN (-6012 4058);
FORCEPROP 2 LAST CDS_LIB mstr_standard
J 0
(-5950 4050);
DISPLAY 0.723404 (-5950 4050);
PAINT MONO (-5950 4050);
DISPLAY INVISIBLE (-5950 4050);
FORCEPROP 1 LAST BODY_TYPE PLUMBING
J 0
(-5950 4100);
DISPLAY 0.872340 (-5950 4100);
PAINT GREEN (-5950 4100);
DISPLAY INVISIBLE (-5950 4100);
FORCEPROP 1 LAST HDL_TAP TRUE
J 0
(-5625 3925);
DISPLAY 0.872340 (-5625 3925);
DISPLAY INVISIBLE (-5625 3925);
FORCEPROP 1 LAST PATH I98
J 0
(-5952 4050);
DISPLAY 0.872340 (-5952 4050);
PAINT GREEN (-5952 4050);
DISPLAY INVISIBLE (-5952 4050);
FORCEADD TAP..1
(-5950 4100);
FORCEPROP 3 LASTPIN (-6000 4100) SIG_NAME M_H_CPU1_SA_DQ<5>
J 0
(-5990 4110);
DISPLAY 0.659574 (-5990 4110);
PAINT MONO (-5990 4110);
DISPLAY INVISIBLE (-5990 4110);
FORCEPROP 1 LASTPIN (-6000 4100) BN 5
J 0
(-6012 4108);
DISPLAY 0.489362 (-6012 4108);
PAINT GREEN (-6012 4108);
FORCEPROP 2 LAST CDS_LIB mstr_standard
J 0
(-5950 4100);
DISPLAY 0.723404 (-5950 4100);
PAINT MONO (-5950 4100);
DISPLAY INVISIBLE (-5950 4100);
FORCEPROP 1 LAST BODY_TYPE PLUMBING
J 0
(-5950 4150);
DISPLAY 0.872340 (-5950 4150);
PAINT GREEN (-5950 4150);
DISPLAY INVISIBLE (-5950 4150);
FORCEPROP 1 LAST HDL_TAP TRUE
J 0
(-5625 3975);
DISPLAY 0.872340 (-5625 3975);
DISPLAY INVISIBLE (-5625 3975);
FORCEPROP 1 LAST PATH I99
J 0
(-5952 4100);
DISPLAY 0.872340 (-5952 4100);
PAINT GREEN (-5952 4100);
DISPLAY INVISIBLE (-5952 4100);
FORCEADD DNS..2
(-8325 2300);
PAINT RED (-8325 2300);
FORCEPROP 2 LAST CDS_LIB mstr_misc
J 0
(-8325 2300);
DISPLAY INVISIBLE (-8325 2300);
FORCEPROP 1 LAST COMMENT_BODY TRUE
R 1
J 0
(-8250 2075);
DISPLAY 0.872340 (-8250 2075);
PAINT PEACH (-8250 2075);
DISPLAY INVISIBLE (-8250 2075);
FORCEADD QUANTA_TITLE_BLOCK_C..1
(0 0);
FORCEPROP 0 LAST CDS_CON_LAST_MODIFIED Thu Sep 14 16:12:12 2023
J 0
(-1885 15);
DISPLAY INVISIBLE (-1885 15);
FORCEPROP 1 LAST CUSTOM_TXT_CDS <CON_LAST_MODIFIED>
J 0
(-1885 15);
DISPLAY 0.978723 (-1885 15);
FORCEPROP 2 LAST CUSTOM_TXT_CDS <XR_PAGE_TITLE>
J 0
(-7890 5250);
DISPLAY 0.638298 (-7890 5250);
PAINT PINK (-7890 5250);
DISPLAY INVISIBLE (-7890 5250);
FORCEPROP 1 LAST CUSTOM_TXT_CDS <NAME_2>
J 0
(-3175 50);
FORCEPROP 1 LAST CUSTOM_TXT_CDS <NAME_1>
J 0
(-3175 175);
FORCEPROP 1 LAST CUSTOM_TXT_CDS <Q_NUMBER>
J 0
(-1403 103);
DISPLAY 1.212766 (-1403 103);
FORCEPROP 1 LAST CUSTOM_TXT_CDS <Q_PROJ>
J 0
(-2382 102);
DISPLAY 1.212766 (-2382 102);
FORCEPROP 1 LAST CUSTOM_TXT_CDS <Q_REV>
J 0
(-184 103);
DISPLAY 1.212766 (-184 103);
FORCEPROP 1 LAST CUSTOM_TXT_CDS <CON_PAGE_NUM> OF <CON_TOTAL_PAGES>
J 0
(-446 18);
DISPLAY 0.978723 (-446 18);
FORCEPROP 1 LAST Q_TITLE DDR5 - CPU1 CHH
J 0
(-9366 26);
DISPLAY 2.446809 (-9366 26);
PAINT GREEN (-9366 26);
FORCEPROP 2 LAST PAGE_BORDER TRUE
J 0
(-7890 5250);
DISPLAY 0.638298 (-7890 5250);
PAINT PINK (-7890 5250);
DISPLAY INVISIBLE (-7890 5250);
FORCEPROP 1 LAST CDS_LMAN_SYM_OUTLINE -9475,6775,100,-125
J 0
(0 0);
DISPLAY 0.468085 (0 0);
PAINT GREEN (0 0);
DISPLAY INVISIBLE (0 0);
FORCEPROP 2 LAST CDS_LIB pure_quanta
J 0
(0 0);
DISPLAY INVISIBLE (0 0);
FORCEPROP 2 LAST CDS_XR_PAGE_TITLE CR-105 : @T6G_MB_LIB.T6G(SCH_1):PAGE105
J 0
(-7890 5250);
DISPLAY 0.638298 (-7890 5250);
PAINT PINK (-7890 5250);
DISPLAY INVISIBLE (-7890 5250);
FORCEPROP 1 LAST Q_DEPT BU9
J 1
(-3763 49);
DISPLAY 1.957447 (-3763 49);
PAINT GREEN (-3763 49);
DISPLAY INVISIBLE (-3763 49);
FORCEPROP 1 LAST COMMENT_BODY TRUE
J 0
(12 -13);
DISPLAY 0.978723 (12 -13);
PAINT GREEN (12 -13);
DISPLAY INVISIBLE (12 -13);
WIRE 17 -1 (-7700 3575)(-7700 3600);
WIRE 17 -1 (-7700 3575)(-7700 3525);
WIRE 17 -1 (-7700 3600)(-8200 3600);
FORCEPROP 2 LAST SIG_NAME M_H_CPU1_SB_CB<7:0>
J 0
(-8150 3610);
DISPLAY 0.489362 (-8150 3610);
WIRE 17 -1 (-7700 3725)(-7700 3775);
WIRE 17 -1 (-7700 3675)(-7700 3725);
WIRE 17 -1 (-7700 3775)(-7700 3825);
WIRE 17 -1 (-7700 3825)(-7700 3875);
WIRE 17 -1 (-7700 3925)(-7700 3875);
WIRE 17 -1 (-7700 3925)(-7700 3975);
WIRE 17 -1 (-7700 4025)(-7700 3975);
WIRE 17 -1 (-7700 4025)(-7700 4050);
WIRE 17 -1 (-7700 4050)(-8200 4050);
FORCEPROP 2 LAST SIG_NAME M_H_CPU1_SA_CB<7:0>
J 0
(-8150 4060);
DISPLAY 0.489362 (-8150 4060);
WIRE 17 -1 (-5900 4625)(-5900 4675);
WIRE 17 -1 (-5900 4575)(-5900 4625);
WIRE 17 -1 (-5900 4725)(-5900 4675);
WIRE 17 -1 (-5900 4775)(-5900 4725);
WIRE 17 -1 (-5900 4525)(-5900 4575);
WIRE 17 -1 (-5900 4475)(-5900 4525);
WIRE 17 -1 (-5900 4825)(-5900 4775);
WIRE 17 -1 (-5900 4875)(-5900 4825);
WIRE 17 -1 (-5900 4475)(-5900 4425);
WIRE 17 -1 (-5900 4425)(-5900 4375);
WIRE 17 -1 (-5900 4925)(-5900 4875);
WIRE 17 -1 (-5900 4975)(-5900 4925);
WIRE 17 -1 (-5900 4375)(-5900 4325);
WIRE 17 -1 (-5900 4325)(-5900 4275);
WIRE 17 -1 (-5900 5025)(-5900 4975);
WIRE 17 -1 (-5900 5075)(-5900 5025);
WIRE 17 -1 (-5900 4275)(-5900 4225);
WIRE 17 -1 (-5900 4225)(-5900 4175);
WIRE 17 -1 (-5900 5125)(-5900 5075);
WIRE 17 -1 (-5900 5175)(-5900 5125);
WIRE 17 -1 (-5900 4175)(-5900 4125);
WIRE 17 -1 (-5900 4125)(-5900 4075);
WIRE 17 -1 (-5900 5225)(-5900 5175);
WIRE 17 -1 (-5900 5275)(-5900 5225);
WIRE 17 -1 (-5900 4025)(-5900 4075);
WIRE 17 -1 (-5900 3975)(-5900 4025);
WIRE 17 -1 (-5900 5325)(-5900 5275);
WIRE 17 -1 (-5900 5375)(-5900 5325);
WIRE 17 -1 (-5900 3925)(-5900 3975);
WIRE 17 -1 (-5900 3875)(-5900 3925);
WIRE 17 -1 (-5900 5425)(-5900 5375);
WIRE 17 -1 (-5900 5450)(-5900 5425);
WIRE 17 -1 (-5900 5450)(-5375 5450);
FORCEPROP 2 LAST SIG_NAME M_H_CPU1_SA_DQ<31:0>
J 0
(-5835 5460);
DISPLAY 0.489362 (-5835 5460);
WIRE 17 -1 (-3175 4425)(-3175 4400);
WIRE 17 -1 (-3175 4425)(-2475 4425);
FORCEPROP 2 LAST SIG_NAME M_H_CPU1_SA_DQS_DN<9:0>
J 0
(-3110 4435);
DISPLAY 0.489362 (-3110 4435);
WIRE 17 -1 (-3375 3425)(-3375 3400);
WIRE 17 -1 (-3375 3425)(-2475 3425);
FORCEPROP 2 LAST SIG_NAME M_H_CPU1_SB_DQS_DP<9:0>
J 0
(-3110 3435);
DISPLAY 0.489362 (-3110 3435);
WIRE 17 -1 (-3175 3375)(-3175 3350);
WIRE 17 -1 (-3175 3375)(-2475 3375);
FORCEPROP 2 LAST SIG_NAME M_H_CPU1_SB_DQS_DN<9:0>
J 0
(-3110 3385);
DISPLAY 0.489362 (-3110 3385);
WIRE 17 -1 (-3375 4475)(-3375 4450);
WIRE 17 -1 (-3375 4475)(-2475 4475);
FORCEPROP 2 LAST SIG_NAME M_H_CPU1_SA_DQS_DP<9:0>
J 0
(-3110 4485);
DISPLAY 0.489362 (-3110 4485);
WIRE 17 -1 (-3375 4450)(-3375 4350);
WIRE 17 -1 (-3375 4350)(-3375 4250);
WIRE 17 -1 (-3375 4250)(-3375 4150);
WIRE 17 -1 (-3175 4400)(-3175 4300);
WIRE 17 -1 (-3175 4300)(-3175 4200);
WIRE 17 -1 (-3175 4200)(-3175 4100);
WIRE 17 -1 (-3175 3250)(-3175 3150);
WIRE 17 -1 (-3175 3350)(-3175 3250);
WIRE 17 -1 (-3175 3150)(-3175 3050);
WIRE 17 -1 (-3175 3050)(-3175 2950);
WIRE 17 -1 (-3375 4150)(-3375 4050);
WIRE 17 -1 (-3375 3200)(-3375 3100);
WIRE 17 -1 (-3375 3300)(-3375 3200);
WIRE 17 -1 (-3375 3100)(-3375 3000);
WIRE 17 -1 (-3375 2900)(-3375 3000);
WIRE 17 -1 (-3375 3400)(-3375 3300);
WIRE 17 -1 (-3375 2800)(-3375 2900);
WIRE 17 -1 (-3375 2700)(-3375 2800);
WIRE 17 -1 (-3175 2850)(-3175 2950);
WIRE 17 -1 (-3175 2750)(-3175 2850);
WIRE 17 -1 (-3175 2650)(-3175 2750);
WIRE 17 -1 (-3175 4100)(-3175 4000);
WIRE 17 -1 (-3175 3900)(-3175 4000);
WIRE 17 -1 (-3175 3800)(-3175 3900);
WIRE 17 -1 (-3175 3700)(-3175 3800);
WIRE 17 -1 (-3375 2700)(-3375 2600);
WIRE 17 -1 (-3175 2650)(-3175 2550);
WIRE 17 -1 (-3375 3950)(-3375 4050);
WIRE 17 -1 (-3375 3850)(-3375 3950);
WIRE 17 -1 (-3375 3750)(-3375 3850);
WIRE 17 -1 (-3375 3750)(-3375 3650);
WIRE 17 -1 (-3175 3700)(-3175 3600);
WIRE 17 -1 (-3375 2600)(-3375 2500);
WIRE 17 -1 (-3175 2550)(-3175 2450);
WIRE 17 -1 (-3375 3650)(-3375 3550);
WIRE 17 -1 (-3175 3600)(-3175 3500);
WIRE 17 -1 (-7700 5325)(-7700 5375);
WIRE 17 -1 (-7700 5275)(-7700 5325);
WIRE 17 -1 (-7700 5375)(-7700 5425);
WIRE 17 -1 (-7700 5425)(-7700 5450);
WIRE 17 -1 (-7700 5225)(-7700 5275);
WIRE 17 -1 (-7700 5175)(-7700 5225);
WIRE 17 -1 (-7700 5450)(-8200 5450);
FORCEPROP 2 LAST SIG_NAME M_H_CPU1_SA_CA<6:0>
J 0
(-8185 5460);
DISPLAY 0.489362 (-8185 5460);
WIRE 17 -1 (-5900 2225)(-5900 2275);
WIRE 17 -1 (-5900 2275)(-5900 2325);
WIRE 17 -1 (-5900 2325)(-5900 2375);
WIRE 17 -1 (-5900 2375)(-5900 2425);
WIRE 17 -1 (-5900 2475)(-5900 2425);
WIRE 17 -1 (-5900 2525)(-5900 2475);
WIRE 17 -1 (-5900 2575)(-5900 2525);
WIRE 17 -1 (-5900 2625)(-5900 2575);
WIRE 17 -1 (-5900 2675)(-5900 2625);
WIRE 17 -1 (-5900 2725)(-5900 2675);
WIRE 17 -1 (-5900 2775)(-5900 2725);
WIRE 17 -1 (-5900 2825)(-5900 2775);
WIRE 17 -1 (-5900 2825)(-5900 2875);
WIRE 17 -1 (-5900 2875)(-5900 2925);
WIRE 17 -1 (-5900 2925)(-5900 2975);
WIRE 17 -1 (-5900 2975)(-5900 3025);
WIRE 17 -1 (-5900 3075)(-5900 3025);
WIRE 17 -1 (-5900 3125)(-5900 3075);
WIRE 17 -1 (-5900 3175)(-5900 3125);
WIRE 17 -1 (-5900 3225)(-5900 3175);
WIRE 17 -1 (-5900 3275)(-5900 3225);
WIRE 17 -1 (-5900 3325)(-5900 3275);
WIRE 17 -1 (-5900 3375)(-5900 3325);
WIRE 17 -1 (-5900 3425)(-5900 3375);
WIRE 17 -1 (-5900 3475)(-5900 3425);
WIRE 17 -1 (-5900 3525)(-5900 3475);
WIRE 17 -1 (-5900 3575)(-5900 3525);
WIRE 17 -1 (-5900 3625)(-5900 3575);
WIRE 17 -1 (-5900 3675)(-5900 3625);
WIRE 17 -1 (-5900 3725)(-5900 3675);
WIRE 17 -1 (-5900 3775)(-5900 3725);
WIRE 17 -1 (-5900 3800)(-5900 3775);
WIRE 17 -1 (-5900 3800)(-5375 3800);
FORCEPROP 2 LAST SIG_NAME M_H_CPU1_SB_DQ<31:0>
J 0
(-5835 3810);
DISPLAY 0.489362 (-5835 3810);
WIRE 17 -1 (-7700 3275)(-7700 3325);
WIRE 17 -1 (-7700 3225)(-7700 3275);
WIRE 17 -1 (-7700 3325)(-7700 3375);
WIRE 17 -1 (-7700 3375)(-7700 3425);
WIRE 17 -1 (-7700 3475)(-7700 3425);
WIRE 17 -1 (-7700 3475)(-7700 3525);
WIRE 17 -1 (-7700 4975)(-7700 5025);
WIRE 17 -1 (-7700 4925)(-7700 4975);
WIRE 17 -1 (-7700 5025)(-7700 5050);
WIRE 17 -1 (-7700 5050)(-8200 5050);
FORCEPROP 2 LAST SIG_NAME M_H_CPU1_SB_CA<6:0>
J 0
(-8185 5060);
DISPLAY 0.489362 (-8185 5060);
WIRE 17 -1 (-7700 4875)(-7700 4925);
WIRE 17 -1 (-7700 4825)(-7700 4875);
WIRE 17 -1 (-7700 4775)(-7700 4825);
WIRE 17 -1 (-7700 4725)(-7700 4775);
WIRE 17 -1 (-7700 5125)(-7700 5175);
WIRE 16 -1 (-6375 900)(-6375 975);
WIRE 16 -1 (-8575 3050)(-8575 3125);
WIRE 16 -1 (-8350 2400)(-8350 2425);
WIRE 16 -1 (-8100 2150)(-8100 2550);
WIRE 16 -1 (-8100 2150)(-8350 2150);
WIRE 16 -1 (-7400 2550)(-8100 2550);
FORCEPROP 2 LAST SIG_NAME PWRGD_CHH_CPU1_DIMM
J 0
(-7975 2560);
DISPLAY 0.489362 (-7975 2560);
FORCEPROP 2 LASTPROP $XRERR UNIQUE?
J 0
(-8215 2560);
DISPLAY 0.638298 (-8215 2560);
PAINT MONO (-8215 2560);
DISPLAY INVISIBLE (-8215 2560);
WIRE 16 -1 (-8350 2200)(-8350 2150);
WIRE 16 -1 (-8350 2150)(-8375 2150);
WIRE 16 -1 (-7400 3050)(-8050 3050);
FORCEPROP 2 LAST SIG_NAME M_H_CPU1_ALERT_N
J 0
(-8035 3060);
DISPLAY 0.489362 (-8035 3060);
WIRE 16 -1 (-7400 3100)(-8050 3100);
FORCEPROP 2 LAST SIG_NAME M_H_CPU1_RESET_N
J 0
(-8035 3110);
DISPLAY 0.489362 (-8035 3110);
WIRE 16 -1 (-7400 3200)(-7600 3200);
WIRE 16 -1 (-6200 2950)(-6000 2950);
WIRE 16 -1 (-7400 3650)(-7600 3650);
WIRE 16 -1 (-6375 1250)(-6375 1175);
WIRE 16 -1 (-6375 1250)(-7100 1250);
FORCEPROP 2 LAST SIG_NAME PD_CHH_CPU1_DIMM_SAA
J 0
(-7085 1260);
DISPLAY 0.489362 (-7085 1260);
WIRE 16 -1 (-6200 5400)(-6000 5400);
WIRE 16 -1 (-7400 4000)(-7600 4000);
WIRE 16 -1 (-7400 3850)(-7600 3850);
WIRE 16 -1 (-7400 5100)(-7600 5100);
WIRE 16 -1 (-7400 4700)(-7600 4700);
WIRE 16 -1 (-7400 5150)(-7600 5150);
WIRE 16 -1 (-7400 4750)(-7600 4750);
WIRE 16 -1 (-7400 5200)(-7600 5200);
WIRE 16 -1 (-7400 4800)(-7600 4800);
WIRE 16 -1 (-7400 5250)(-7600 5250);
WIRE 16 -1 (-7400 4850)(-7600 4850);
WIRE 16 -1 (-7400 4900)(-7600 4900);
WIRE 16 -1 (-7400 4950)(-7600 4950);
WIRE 16 -1 (-7400 5400)(-7600 5400);
WIRE 16 -1 (-7400 5000)(-7600 5000);
WIRE 16 -1 (-7400 3950)(-7600 3950);
WIRE 16 -1 (-7400 3900)(-7600 3900);
WIRE 16 -1 (-7400 3800)(-7600 3800);
WIRE 16 -1 (-7400 3750)(-7600 3750);
WIRE 16 -1 (-7400 3500)(-7600 3500);
WIRE 16 -1 (-7400 3450)(-7600 3450);
WIRE 16 -1 (-7400 3400)(-7600 3400);
WIRE 16 -1 (-7400 3350)(-7600 3350);
WIRE 16 -1 (-7400 3300)(-7600 3300);
WIRE 16 -1 (-7400 3250)(-7600 3250);
WIRE 16 -1 (-7400 4100)(-8200 4100);
FORCEPROP 2 LAST SIG_NAME M_H_CPU1_CLK_DN<0>
J 0
(-8150 4110);
DISPLAY 0.489362 (-8150 4110);
WIRE 16 -1 (-7400 4150)(-8200 4150);
FORCEPROP 2 LAST SIG_NAME M_H_CPU1_CLK_DP<0>
J 0
(-8150 4160);
DISPLAY 0.489362 (-8150 4160);
WIRE 16 -1 (-7400 4400)(-8200 4400);
FORCEPROP 2 LAST SIG_NAME M_H_CPU1_SA_CS_N<0>
J 0
(-8150 4410);
DISPLAY 0.489362 (-8150 4410);
WIRE 16 -1 (-7400 4250)(-8200 4250);
FORCEPROP 2 LAST SIG_NAME M_H_CPU1_SB_CS_N<0>
J 0
(-8150 4260);
DISPLAY 0.489362 (-8150 4260);
WIRE 16 -1 (-7400 4450)(-8200 4450);
FORCEPROP 2 LAST SIG_NAME M_H_CPU1_SA_CS_N<1>
J 0
(-8150 4460);
DISPLAY 0.489362 (-8150 4460);
WIRE 16 -1 (-7400 4300)(-8200 4300);
FORCEPROP 2 LAST SIG_NAME M_H_CPU1_SB_CS_N<1>
J 0
(-8150 4310);
DISPLAY 0.489362 (-8150 4310);
WIRE 16 -1 (-6200 5200)(-6000 5200);
WIRE 16 -1 (-6000 5150)(-6200 5150);
WIRE 16 -1 (-6000 5100)(-6200 5100);
WIRE 16 -1 (-6000 5050)(-6200 5050);
WIRE 16 -1 (-6200 5000)(-6000 5000);
WIRE 16 -1 (-6000 4950)(-6200 4950);
WIRE 16 -1 (-6000 4900)(-6200 4900);
WIRE 16 -1 (-6000 4850)(-6200 4850);
WIRE 16 -1 (-6200 4800)(-6000 4800);
WIRE 16 -1 (-6000 4750)(-6200 4750);
WIRE 16 -1 (-6000 4700)(-6200 4700);
WIRE 16 -1 (-6000 4550)(-6200 4550);
WIRE 16 -1 (-6000 4500)(-6200 4500);
WIRE 16 -1 (-6000 4450)(-6200 4450);
WIRE 16 -1 (-6200 4400)(-6000 4400);
WIRE 16 -1 (-6000 4350)(-6200 4350);
WIRE 16 -1 (-6000 4300)(-6200 4300);
WIRE 16 -1 (-6000 4250)(-6200 4250);
WIRE 16 -1 (-6200 4200)(-6000 4200);
WIRE 16 -1 (-6000 4150)(-6200 4150);
WIRE 16 -1 (-6000 4100)(-6200 4100);
WIRE 16 -1 (-6000 4050)(-6200 4050);
WIRE 16 -1 (-6200 4000)(-6000 4000);
WIRE 16 -1 (-6000 3950)(-6200 3950);
WIRE 16 -1 (-6000 3900)(-6200 3900);
WIRE 16 -1 (-6000 3850)(-6200 3850);
WIRE 16 -1 (-6200 3750)(-6000 3750);
WIRE 16 -1 (-6000 3700)(-6200 3700);
WIRE 16 -1 (-6000 3650)(-6200 3650);
WIRE 16 -1 (-6000 3600)(-6200 3600);
WIRE 16 -1 (-6200 3550)(-6000 3550);
WIRE 16 -1 (-6000 3500)(-6200 3500);
WIRE 16 -1 (-6000 3450)(-6200 3450);
WIRE 16 -1 (-6000 3400)(-6200 3400);
WIRE 16 -1 (-6200 3350)(-6000 3350);
WIRE 16 -1 (-6000 3300)(-6200 3300);
WIRE 16 -1 (-6000 3250)(-6200 3250);
WIRE 16 -1 (-6000 3200)(-6200 3200);
WIRE 16 -1 (-6200 3150)(-6000 3150);
WIRE 16 -1 (-6000 3100)(-6200 3100);
WIRE 16 -1 (-6000 3050)(-6200 3050);
WIRE 16 -1 (-6000 3000)(-6200 3000);
WIRE 16 -1 (-6000 2900)(-6200 2900);
WIRE 16 -1 (-6000 2850)(-6200 2850);
WIRE 16 -1 (-6000 2800)(-6200 2800);
WIRE 16 -1 (-6200 2750)(-6000 2750);
WIRE 16 -1 (-6000 2700)(-6200 2700);
WIRE 16 -1 (-6000 2650)(-6200 2650);
WIRE 16 -1 (-6000 2600)(-6200 2600);
WIRE 16 -1 (-6200 2550)(-6000 2550);
WIRE 16 -1 (-6000 2500)(-6200 2500);
WIRE 16 -1 (-6000 2450)(-6200 2450);
WIRE 16 -1 (-6000 2400)(-6200 2400);
WIRE 16 -1 (-6200 2350)(-6000 2350);
WIRE 16 -1 (-6000 2300)(-6200 2300);
WIRE 16 -1 (-6000 2250)(-6200 2250);
WIRE 16 -1 (-6000 2200)(-6200 2200);
WIRE 16 -1 (-7400 2000)(-8200 2000);
FORCEPROP 2 LAST SIG_NAME M_H_CPU1_SA_RSP<0>
J 0
(-8150 2010);
DISPLAY 0.489362 (-8150 2010);
WIRE 16 -1 (-7400 1950)(-8200 1950);
FORCEPROP 2 LAST SIG_NAME M_H_CPU1_SB_RSP<0>
J 0
(-8150 1960);
DISPLAY 0.489362 (-8150 1960);
WIRE 16 -1 (-7400 4600)(-8200 4600);
FORCEPROP 2 LAST SIG_NAME M_H_CPU1_SA_PAR
J 0
(-8150 4610);
DISPLAY 0.489362 (-8150 4610);
WIRE 16 -1 (-7400 4550)(-8200 4550);
FORCEPROP 2 LAST SIG_NAME M_H_CPU1_SB_PAR
J 0
(-8150 4560);
DISPLAY 0.489362 (-8150 4560);
WIRE 16 -1 (-6000 5250)(-6200 5250);
WIRE 16 -1 (-6000 5350)(-6200 5350);
WIRE 16 -1 (-6000 5300)(-6200 5300);
WIRE 16 -1 (-7400 5300)(-7600 5300);
WIRE 16 -1 (-7400 5350)(-7600 5350);
WIRE 16 -1 (-3625 4175)(-3275 4175);
WIRE 16 -1 (-3475 4125)(-3625 4125);
WIRE 16 -1 (-3475 3275)(-3625 3275);
WIRE 16 -1 (-3625 3225)(-3275 3225);
WIRE 16 -1 (-3475 3175)(-3625 3175);
WIRE 16 -1 (-3625 3475)(-3275 3475);
WIRE 16 -1 (-3475 3525)(-3625 3525);
WIRE 16 -1 (-3625 2425)(-3275 2425);
WIRE 16 -1 (-3475 2475)(-3625 2475);
WIRE 16 -1 (-3625 3575)(-3275 3575);
WIRE 16 -1 (-3625 3625)(-3475 3625);
WIRE 16 -1 (-3625 2525)(-3275 2525);
WIRE 16 -1 (-3625 2575)(-3475 2575);
WIRE 16 -1 (-3625 3675)(-3275 3675);
WIRE 16 -1 (-3475 3725)(-3625 3725);
WIRE 16 -1 (-3625 2625)(-3275 2625);
WIRE 16 -1 (-3475 2675)(-3625 2675);
WIRE 16 -1 (-3625 3775)(-3275 3775);
WIRE 16 -1 (-3475 3825)(-3625 3825);
WIRE 16 -1 (-3625 2725)(-3275 2725);
WIRE 16 -1 (-3475 2775)(-3625 2775);
WIRE 16 -1 (-3625 3875)(-3275 3875);
WIRE 16 -1 (-3475 3925)(-3625 3925);
WIRE 16 -1 (-3625 2825)(-3275 2825);
WIRE 16 -1 (-3475 2875)(-3625 2875);
WIRE 16 -1 (-3625 3975)(-3275 3975);
WIRE 16 -1 (-3625 4025)(-3475 4025);
WIRE 16 -1 (-3625 2925)(-3275 2925);
WIRE 16 -1 (-3625 2975)(-3475 2975);
WIRE 16 -1 (-3625 4075)(-3275 4075);
WIRE 16 -1 (-3625 3025)(-3275 3025);
WIRE 16 -1 (-3475 3075)(-3625 3075);
WIRE 16 -1 (-3475 4225)(-3625 4225);
WIRE 16 -1 (-3625 3125)(-3275 3125);
WIRE 16 -1 (-3625 4275)(-3275 4275);
WIRE 16 -1 (-3475 4325)(-3625 4325);
WIRE 16 -1 (-3625 4425)(-3475 4425);
WIRE 16 -1 (-3625 3325)(-3275 3325);
WIRE 16 -1 (-3625 3375)(-3475 3375);
WIRE 16 -1 (-3625 4375)(-3275 4375);
WIRE 16 -1 (-6000 4650)(-6200 4650);
WIRE 16 -1 (-6200 4600)(-6000 4600);
WIRE 16 -1 (-7400 3700)(-7600 3700);
WIRE 16 -1 (-7400 3550)(-7600 3550);
WIRE 16 -1 (-8575 2150)(-8975 2150);
FORCEPROP 2 LAST SIG_NAME PWRGD_CHGL_CPU1
J 0
(-8960 2160);
DISPLAY 0.489362 (-8960 2160);
WIRE 16 -1 (-2250 6075)(-2125 6075);
WIRE 16 -1 (-2250 6075)(-2250 5975);
WIRE 16 -1 (-2250 6075)(-2825 6075);
WIRE 16 -1 (-2125 5300)(-2125 6075);
WIRE 16 -1 (-1825 5300)(-2125 5300);
WIRE 16 -1 (-2125 5250)(-2125 5300);
WIRE 16 -1 (-2825 5975)(-2825 6075);
WIRE 16 -1 (-2825 6075)(-2825 6150);
WIRE 16 -1 (-1825 5250)(-2125 5250);
WIRE 16 -1 (-2125 5250)(-2125 5200);
WIRE 16 -1 (-2125 5200)(-1825 5200);
WIRE 16 -1 (-2250 5650)(-2250 5775);
WIRE 16 -1 (-2250 5650)(-2825 5650);
WIRE 16 -1 (-2825 5650)(-2825 5775);
WIRE 16 -1 (-2825 5650)(-2825 5575);
WIRE 16 -1 (-325 2150)(-325 2050);
WIRE 16 -1 (-325 2200)(-325 2150);
WIRE 16 -1 (-325 2150)(-625 2150);
WIRE 16 -1 (-325 2050)(-625 2050);
WIRE 16 -1 (-325 2050)(-325 2000);
WIRE 16 -1 (-325 2000)(-325 1950);
WIRE 16 -1 (-325 2000)(-625 2000);
WIRE 16 -1 (-325 2250)(-325 2200);
WIRE 16 -1 (-325 2200)(-625 2200);
WIRE 16 -1 (-325 2300)(-325 2250);
WIRE 16 -1 (-325 2250)(-625 2250);
WIRE 16 -1 (-325 1950)(-325 1700);
WIRE 16 -1 (-325 1950)(-625 1950);
WIRE 16 -1 (-325 2350)(-325 2300);
WIRE 16 -1 (-325 2300)(-625 2300);
WIRE 16 -1 (-325 2400)(-325 2350);
WIRE 16 -1 (-325 2350)(-625 2350);
WIRE 16 -1 (-325 2450)(-325 2400);
WIRE 16 -1 (-325 2400)(-625 2400);
WIRE 16 -1 (-325 2500)(-325 2450);
WIRE 16 -1 (-325 2450)(-625 2450);
WIRE 16 -1 (-325 2550)(-325 2500);
WIRE 16 -1 (-325 2500)(-625 2500);
WIRE 16 -1 (-325 2600)(-325 2550);
WIRE 16 -1 (-325 2550)(-625 2550);
WIRE 16 -1 (-325 2650)(-325 2600);
WIRE 16 -1 (-325 2600)(-625 2600);
WIRE 16 -1 (-325 2700)(-325 2650);
WIRE 16 -1 (-325 2650)(-625 2650);
WIRE 16 -1 (-325 2750)(-325 2700);
WIRE 16 -1 (-325 2700)(-625 2700);
WIRE 16 -1 (-325 2800)(-325 2750);
WIRE 16 -1 (-325 2750)(-625 2750);
WIRE 16 -1 (-325 2850)(-325 2800);
WIRE 16 -1 (-325 2800)(-625 2800);
WIRE 16 -1 (-325 2900)(-325 2850);
WIRE 16 -1 (-325 2850)(-625 2850);
WIRE 16 -1 (-325 2950)(-325 2900);
WIRE 16 -1 (-325 2900)(-625 2900);
WIRE 16 -1 (-325 3000)(-325 2950);
WIRE 16 -1 (-325 2950)(-625 2950);
WIRE 16 -1 (-325 3050)(-325 3000);
WIRE 16 -1 (-325 3000)(-625 3000);
WIRE 16 -1 (-325 3100)(-325 3050);
WIRE 16 -1 (-325 3050)(-625 3050);
WIRE 16 -1 (-325 3150)(-325 3100);
WIRE 16 -1 (-325 3100)(-625 3100);
WIRE 16 -1 (-325 3200)(-325 3150);
WIRE 16 -1 (-325 3150)(-625 3150);
WIRE 16 -1 (-325 3250)(-325 3200);
WIRE 16 -1 (-325 3200)(-625 3200);
WIRE 16 -1 (-325 3300)(-325 3250);
WIRE 16 -1 (-325 3250)(-625 3250);
WIRE 16 -1 (-325 3350)(-325 3300);
WIRE 16 -1 (-325 3300)(-625 3300);
WIRE 16 -1 (-325 3400)(-325 3350);
WIRE 16 -1 (-325 3350)(-625 3350);
WIRE 16 -1 (-325 3450)(-325 3400);
WIRE 16 -1 (-325 3400)(-625 3400);
WIRE 16 -1 (-325 3500)(-325 3450);
WIRE 16 -1 (-325 3450)(-625 3450);
WIRE 16 -1 (-325 3550)(-325 3500);
WIRE 16 -1 (-325 3500)(-625 3500);
WIRE 16 -1 (-325 3600)(-325 3550);
WIRE 16 -1 (-325 3550)(-625 3550);
WIRE 16 -1 (-325 3650)(-325 3600);
WIRE 16 -1 (-325 3600)(-625 3600);
WIRE 16 -1 (-325 3700)(-325 3650);
WIRE 16 -1 (-325 3650)(-625 3650);
WIRE 16 -1 (-325 3750)(-325 3700);
WIRE 16 -1 (-325 3700)(-625 3700);
WIRE 16 -1 (-325 3800)(-325 3750);
WIRE 16 -1 (-325 3750)(-625 3750);
WIRE 16 -1 (-325 3850)(-325 3800);
WIRE 16 -1 (-325 3800)(-625 3800);
WIRE 16 -1 (-325 3900)(-325 3850);
WIRE 16 -1 (-325 3850)(-625 3850);
WIRE 16 -1 (-325 3950)(-325 3900);
WIRE 16 -1 (-325 3900)(-625 3900);
WIRE 16 -1 (-325 4000)(-325 3950);
WIRE 16 -1 (-325 3950)(-625 3950);
WIRE 16 -1 (-325 4050)(-325 4000);
WIRE 16 -1 (-325 4000)(-625 4000);
WIRE 16 -1 (-325 4100)(-325 4050);
WIRE 16 -1 (-325 4050)(-625 4050);
WIRE 16 -1 (-325 4150)(-325 4100);
WIRE 16 -1 (-325 4100)(-625 4100);
WIRE 16 -1 (-325 4200)(-325 4150);
WIRE 16 -1 (-325 4150)(-625 4150);
WIRE 16 -1 (-325 4250)(-325 4200);
WIRE 16 -1 (-325 4200)(-625 4200);
WIRE 16 -1 (-325 4300)(-325 4250);
WIRE 16 -1 (-325 4250)(-625 4250);
WIRE 16 -1 (-325 4350)(-325 4300);
WIRE 16 -1 (-325 4300)(-625 4300);
WIRE 16 -1 (-325 4400)(-325 4350);
WIRE 16 -1 (-325 4350)(-625 4350);
WIRE 16 -1 (-325 4450)(-325 4400);
WIRE 16 -1 (-325 4400)(-625 4400);
WIRE 16 -1 (-325 4500)(-325 4450);
WIRE 16 -1 (-325 4450)(-625 4450);
WIRE 16 -1 (-325 4550)(-325 4500);
WIRE 16 -1 (-325 4500)(-625 4500);
WIRE 16 -1 (-325 4600)(-325 4550);
WIRE 16 -1 (-325 4550)(-625 4550);
WIRE 16 -1 (-325 4650)(-325 4600);
WIRE 16 -1 (-325 4600)(-625 4600);
WIRE 16 -1 (-325 4700)(-325 4650);
WIRE 16 -1 (-325 4650)(-625 4650);
WIRE 16 -1 (-325 4750)(-325 4700);
WIRE 16 -1 (-325 4700)(-625 4700);
WIRE 16 -1 (-325 4800)(-325 4750);
WIRE 16 -1 (-325 4750)(-625 4750);
WIRE 16 -1 (-325 4850)(-325 4800);
WIRE 16 -1 (-325 4800)(-625 4800);
WIRE 16 -1 (-325 4900)(-325 4850);
WIRE 16 -1 (-325 4850)(-625 4850);
WIRE 16 -1 (-325 4950)(-325 4900);
WIRE 16 -1 (-325 4900)(-625 4900);
WIRE 16 -1 (-325 5000)(-325 4950);
WIRE 16 -1 (-325 4950)(-625 4950);
WIRE 16 -1 (-325 5050)(-325 5000);
WIRE 16 -1 (-325 5000)(-625 5000);
WIRE 16 -1 (-325 5100)(-325 5050);
WIRE 16 -1 (-325 5050)(-625 5050);
WIRE 16 -1 (-325 5150)(-325 5100);
WIRE 16 -1 (-325 5100)(-625 5100);
WIRE 16 -1 (-325 5200)(-325 5150);
WIRE 16 -1 (-325 5150)(-625 5150);
WIRE 16 -1 (-325 5250)(-325 5200);
WIRE 16 -1 (-325 5200)(-625 5200);
WIRE 16 -1 (-325 5300)(-325 5250);
WIRE 16 -1 (-325 5250)(-625 5250);
WIRE 16 -1 (-325 5300)(-625 5300);
WIRE 16 -1 (-1825 2100)(-2125 2100);
WIRE 16 -1 (-2125 2100)(-2125 2050);
WIRE 16 -1 (-2125 2150)(-2125 2100);
WIRE 16 -1 (-1825 2150)(-2125 2150);
WIRE 16 -1 (-2125 2200)(-2125 2150);
WIRE 16 -1 (-1825 2050)(-2125 2050);
WIRE 16 -1 (-2125 2050)(-2125 1925);
WIRE 16 -1 (-1825 2200)(-2125 2200);
WIRE 16 -1 (-2125 2250)(-2125 2200);
WIRE 16 -1 (-1825 2250)(-2125 2250);
WIRE 16 -1 (-2125 2300)(-2125 2250);
WIRE 16 -1 (-1825 2300)(-2125 2300);
WIRE 16 -1 (-2125 2350)(-2125 2300);
WIRE 16 -1 (-1825 2350)(-2125 2350);
WIRE 16 -1 (-2125 2400)(-2125 2350);
WIRE 16 -1 (-1825 2400)(-2125 2400);
WIRE 16 -1 (-2125 2450)(-2125 2400);
WIRE 16 -1 (-1825 2450)(-2125 2450);
WIRE 16 -1 (-2125 2500)(-2125 2450);
WIRE 16 -1 (-1825 2500)(-2125 2500);
WIRE 16 -1 (-2125 2550)(-2125 2500);
WIRE 16 -1 (-1825 2550)(-2125 2550);
WIRE 16 -1 (-2125 2600)(-2125 2550);
WIRE 16 -1 (-1825 2600)(-2125 2600);
WIRE 16 -1 (-2125 2650)(-2125 2600);
WIRE 16 -1 (-1825 2650)(-2125 2650);
WIRE 16 -1 (-2125 2700)(-2125 2650);
WIRE 16 -1 (-1825 2700)(-2125 2700);
WIRE 16 -1 (-2125 2750)(-2125 2700);
WIRE 16 -1 (-1825 2750)(-2125 2750);
WIRE 16 -1 (-2125 2800)(-2125 2750);
WIRE 16 -1 (-1825 2800)(-2125 2800);
WIRE 16 -1 (-2125 2850)(-2125 2800);
WIRE 16 -1 (-1825 2850)(-2125 2850);
WIRE 16 -1 (-2125 2900)(-2125 2850);
WIRE 16 -1 (-1825 2900)(-2125 2900);
WIRE 16 -1 (-2125 2950)(-2125 2900);
WIRE 16 -1 (-1825 2950)(-2125 2950);
WIRE 16 -1 (-2125 3000)(-2125 2950);
WIRE 16 -1 (-1825 3000)(-2125 3000);
WIRE 16 -1 (-2125 3050)(-2125 3000);
WIRE 16 -1 (-1825 3050)(-2125 3050);
WIRE 16 -1 (-2125 3100)(-2125 3050);
WIRE 16 -1 (-1825 3100)(-2125 3100);
WIRE 16 -1 (-2125 3150)(-2125 3100);
WIRE 16 -1 (-1825 3150)(-2125 3150);
WIRE 16 -1 (-2125 3200)(-2125 3150);
WIRE 16 -1 (-1825 3200)(-2125 3200);
WIRE 16 -1 (-2125 3250)(-2125 3200);
WIRE 16 -1 (-1825 3250)(-2125 3250);
WIRE 16 -1 (-2125 3300)(-2125 3250);
WIRE 16 -1 (-1825 3300)(-2125 3300);
WIRE 16 -1 (-2125 3350)(-2125 3300);
WIRE 16 -1 (-1825 3350)(-2125 3350);
WIRE 16 -1 (-2125 3400)(-2125 3350);
WIRE 16 -1 (-1825 3400)(-2125 3400);
WIRE 16 -1 (-2125 3450)(-2125 3400);
WIRE 16 -1 (-1825 3450)(-2125 3450);
WIRE 16 -1 (-2125 3500)(-2125 3450);
WIRE 16 -1 (-1825 3500)(-2125 3500);
WIRE 16 -1 (-2125 3550)(-2125 3500);
WIRE 16 -1 (-1825 3550)(-2125 3550);
WIRE 16 -1 (-2125 3600)(-2125 3550);
WIRE 16 -1 (-1825 3600)(-2125 3600);
WIRE 16 -1 (-2125 3650)(-2125 3600);
WIRE 16 -1 (-1825 3650)(-2125 3650);
WIRE 16 -1 (-2125 3700)(-2125 3650);
WIRE 16 -1 (-1825 3700)(-2125 3700);
WIRE 16 -1 (-2125 3750)(-2125 3700);
WIRE 16 -1 (-1825 3750)(-2125 3750);
WIRE 16 -1 (-2125 3800)(-2125 3750);
WIRE 16 -1 (-1825 3800)(-2125 3800);
WIRE 16 -1 (-2125 3850)(-2125 3800);
WIRE 16 -1 (-1825 3850)(-2125 3850);
WIRE 16 -1 (-2125 3900)(-2125 3850);
WIRE 16 -1 (-1825 3900)(-2125 3900);
WIRE 16 -1 (-2125 3950)(-2125 3900);
WIRE 16 -1 (-1825 3950)(-2125 3950);
WIRE 16 -1 (-2125 4000)(-2125 3950);
WIRE 16 -1 (-1825 4000)(-2125 4000);
WIRE 16 -1 (-2125 4050)(-2125 4000);
WIRE 16 -1 (-2125 4100)(-2125 4050);
WIRE 16 -1 (-1825 4050)(-2125 4050);
WIRE 16 -1 (-1825 4100)(-2125 4100);
WIRE 16 -1 (-2125 4150)(-2125 4100);
WIRE 16 -1 (-1825 4150)(-2125 4150);
WIRE 16 -1 (-2125 4200)(-2125 4150);
WIRE 16 -1 (-1825 4200)(-2125 4200);
WIRE 16 -1 (-2125 4250)(-2125 4200);
WIRE 16 -1 (-1825 4250)(-2125 4250);
WIRE 16 -1 (-2125 4300)(-2125 4250);
WIRE 16 -1 (-1825 4300)(-2125 4300);
WIRE 16 -1 (-2125 4350)(-2125 4300);
WIRE 16 -1 (-1825 4350)(-2125 4350);
WIRE 16 -1 (-2125 4400)(-2125 4350);
WIRE 16 -1 (-1825 4400)(-2125 4400);
WIRE 16 -1 (-2125 4450)(-2125 4400);
WIRE 16 -1 (-1825 4450)(-2125 4450);
WIRE 16 -1 (-2125 4500)(-2125 4450);
WIRE 16 -1 (-1825 4500)(-2125 4500);
WIRE 16 -1 (-2125 4550)(-2125 4500);
WIRE 16 -1 (-1825 4550)(-2125 4550);
WIRE 16 -1 (-2125 4600)(-2125 4550);
WIRE 16 -1 (-1825 4600)(-2125 4600);
WIRE 16 -1 (-2125 4650)(-2125 4600);
WIRE 16 -1 (-1825 4650)(-2125 4650);
WIRE 16 -1 (-2125 4700)(-2125 4650);
WIRE 16 -1 (-1825 4700)(-2125 4700);
WIRE 16 -1 (-2125 4750)(-2125 4700);
WIRE 16 -1 (-1825 4750)(-2125 4750);
WIRE 16 -1 (-2125 4800)(-2125 4750);
WIRE 16 -1 (-1825 4800)(-2125 4800);
WIRE 16 -1 (-2125 4850)(-2125 4800);
WIRE 16 -1 (-1825 4850)(-2125 4850);
WIRE 16 -1 (-2125 4900)(-2125 4850);
WIRE 16 -1 (-1825 4900)(-2125 4900);
WIRE 16 -1 (-2125 4950)(-2125 4900);
WIRE 16 -1 (-1825 4950)(-2125 4950);
WIRE 16 -1 (-2125 5000)(-2125 4950);
WIRE 16 -1 (-1825 5000)(-2125 5000);
WIRE 16 -1 (-2125 5050)(-2125 5000);
WIRE 16 -1 (-1825 5050)(-2125 5050);
WIRE 16 -1 (-2125 5100)(-2125 5050);
WIRE 16 -1 (-1825 5100)(-2125 5100);
WIRE 16 -1 (-2125 5150)(-2125 5100);
WIRE 16 -1 (-1825 5150)(-2125 5150);
WIRE 16 -1 (-7400 2900)(-8500 2900);
FORCEPROP 2 LAST SIG_NAME PD_CHH_CPU1_DIMM_SAA
J 0
(-8475 2910);
DISPLAY 0.489362 (-8475 2910);
WIRE 16 -1 (-7500 2625)(-7600 2625);
WIRE 16 -1 (-7500 2800)(-7500 2625);
WIRE 16 -1 (-7400 2800)(-7500 2800);
FORCEPROP 2 LAST SIG_NAME I3C_SPD_DDRH_CPU1_SCL
J 0
(-7885 2810);
DISPLAY 0.446809 (-7885 2810);
FORCEPROP 2 LASTPROP $XRERR UNIQUE?
J 0
(-8125 2810);
DISPLAY 0.638298 (-8125 2810);
PAINT MONO (-8125 2810);
DISPLAY INVISIBLE (-8125 2810);
WIRE 16 -1 (-8175 2850)(-8150 2850);
WIRE 16 -1 (-8175 2725)(-8175 2850);
WIRE 16 -1 (-8175 2725)(-8675 2725);
FORCEPROP 2 LAST SIG_NAME I3C_SPD_DDRGL_CPU1_SDA
J 0
(-8685 2735);
DISPLAY 0.489362 (-8685 2735);
WIRE 16 -1 (-7800 2625)(-8275 2625);
FORCEPROP 2 LAST SIG_NAME I3C_SPD_DDRGL_CPU1_SCL
J 0
(-8310 2635);
DISPLAY 0.489362 (-8310 2635);
WIRE 16 -1 (-7400 2850)(-7950 2850);
FORCEPROP 2 LAST SIG_NAME I3C_SPD_DDRH_CPU1_SDA
J 0
(-7885 2860);
DISPLAY 0.446809 (-7885 2860);
FORCEPROP 2 LASTPROP $XRERR UNIQUE?
J 0
(-8125 2860);
DISPLAY 0.638298 (-8125 2860);
PAINT MONO (-8125 2860);
DISPLAY INVISIBLE (-8125 2860);
WIRE 16 -1 (-8475 2950)(-7400 2950);
WIRE 16 -1 (-8475 3350)(-8475 2950);
WIRE 16 -1 (-8475 3375)(-8475 3350);
WIRE 16 -1 (-8575 3350)(-8475 3350);
WIRE 16 -1 (-8575 3325)(-8575 3350);
DOT 1 (-8475 3350);
DOT 1 (-2125 4950);
DOT 1 (-2125 5000);
DOT 1 (-2825 6075);
DOT 1 (-2250 6075);
DOT 1 (-2125 3500);
DOT 1 (-8350 2150);
DOT 1 (-2125 2050);
DOT 1 (-2125 2100);
DOT 1 (-2125 2150);
DOT 1 (-2125 2200);
DOT 1 (-2125 2250);
DOT 1 (-2125 2300);
DOT 1 (-2125 2350);
DOT 1 (-2125 2400);
DOT 1 (-2125 2450);
DOT 1 (-2125 2500);
DOT 1 (-2125 2550);
DOT 1 (-2125 2600);
DOT 1 (-2125 2650);
DOT 1 (-2125 2750);
DOT 1 (-2125 2700);
DOT 1 (-2125 2800);
DOT 1 (-2125 2850);
DOT 1 (-2125 2900);
DOT 1 (-2125 2950);
DOT 1 (-2125 3000);
DOT 1 (-2125 3050);
DOT 1 (-2125 3100);
DOT 1 (-2125 3150);
DOT 1 (-2125 3200);
DOT 1 (-2125 3250);
DOT 1 (-2125 3300);
DOT 1 (-2125 3350);
DOT 1 (-2125 3450);
DOT 1 (-2125 3550);
DOT 1 (-2125 3600);
DOT 1 (-2125 3650);
DOT 1 (-2125 3700);
DOT 1 (-2125 3750);
DOT 1 (-2125 3800);
DOT 1 (-325 1950);
DOT 1 (-325 2000);
DOT 1 (-325 2050);
DOT 1 (-325 2150);
DOT 1 (-325 2250);
DOT 1 (-325 2200);
DOT 1 (-325 2300);
DOT 1 (-325 2350);
DOT 1 (-325 2400);
DOT 1 (-325 2450);
DOT 1 (-325 2500);
DOT 1 (-325 2550);
DOT 1 (-325 2600);
DOT 1 (-325 2650);
DOT 1 (-325 2750);
DOT 1 (-325 2700);
DOT 1 (-325 2800);
DOT 1 (-325 2850);
DOT 1 (-325 2900);
DOT 1 (-325 2950);
DOT 1 (-325 3000);
DOT 1 (-325 3050);
DOT 1 (-325 3100);
DOT 1 (-325 3150);
DOT 1 (-325 3200);
DOT 1 (-325 3250);
DOT 1 (-325 3300);
DOT 1 (-325 3350);
DOT 1 (-325 3400);
DOT 1 (-325 3450);
DOT 1 (-325 3500);
DOT 1 (-325 3550);
DOT 1 (-325 3600);
DOT 1 (-325 3650);
DOT 1 (-325 3700);
DOT 1 (-325 3750);
DOT 1 (-325 3800);
DOT 1 (-2125 3900);
DOT 1 (-2125 3850);
DOT 1 (-2125 3950);
DOT 1 (-2125 4000);
DOT 1 (-2125 4050);
DOT 1 (-2125 4100);
DOT 1 (-2125 4150);
DOT 1 (-2125 4200);
DOT 1 (-2125 4250);
DOT 1 (-2125 4300);
DOT 1 (-2125 4350);
DOT 1 (-2125 4400);
DOT 1 (-2125 4500);
DOT 1 (-2125 4550);
DOT 1 (-2125 4600);
DOT 1 (-2125 4650);
DOT 1 (-2125 4700);
DOT 1 (-2125 4800);
DOT 1 (-2125 4750);
DOT 1 (-2125 4850);
DOT 1 (-2125 4900);
DOT 1 (-2125 5250);
DOT 1 (-2125 5300);
DOT 1 (-325 3850);
DOT 1 (-325 3900);
DOT 1 (-325 3950);
DOT 1 (-325 4000);
DOT 1 (-325 4050);
DOT 1 (-325 4100);
DOT 1 (-325 4150);
DOT 1 (-325 4200);
DOT 1 (-325 4250);
DOT 1 (-325 4300);
DOT 1 (-325 4350);
DOT 1 (-325 4400);
DOT 1 (-325 4450);
DOT 1 (-325 4500);
DOT 1 (-325 4550);
DOT 1 (-325 4600);
DOT 1 (-325 4650);
DOT 1 (-325 4700);
DOT 1 (-325 4800);
DOT 1 (-325 4750);
DOT 1 (-325 4850);
DOT 1 (-325 4900);
DOT 1 (-325 4950);
DOT 1 (-325 5000);
DOT 1 (-325 5050);
DOT 1 (-325 5100);
DOT 1 (-325 5150);
DOT 1 (-325 5200);
DOT 1 (-325 5250);
DOT 1 (-2125 3400);
DOT 1 (-2125 4450);
DOT 1 (-2125 5100);
DOT 1 (-2125 5050);
DOT 1 (-2825 5650);
QUIT
